G04 ================== begin FILE IDENTIFICATION RECORD ==================*
G04 Layout Name:  9048_F0T_Management_Board_D_brd_V04_1213_1625.brd*
G04 Film Name:    gnd3*
G04 File Format:  Gerber RS274X*
G04 File Origin:  Cadence Allegro 17.2-S081*
G04 Origin Date:  Tue Dec 13 16:31:12 2022*
G04 *
G04 Layer:  DRAWING FORMAT/TITLE_BLOCK_A*
G04 Layer:  VIA CLASS/GND3*
G04 Layer:  PIN/GND3*
G04 Layer:  MANUFACTURING/PHOTOPLOT_OUTLINE*
G04 Layer:  ETCH/GND3*
G04 Layer:  DRAWING FORMAT/TITLE_BLOCK*
G04 Layer:  DRAWING FORMAT/TITLE_DATA_GND3*
G04 *
G04 Offset:    (0.00 0.00)*
G04 Mirror:    No*
G04 Mode:      Negative*
G04 Rotation:  0*
G04 FullContactRelief:  No*
G04 UndefLineWidth:     6.00*
G04 ================== end FILE IDENTIFICATION RECORD ====================*
%FSLAX25Y25*MOIN*%
%IR0*IPPOS*OFA0.00000B0.00000*MIA0B0*SFA1.00000B1.00000*%
%ADD19C,.03*%
%ADD25C,.052*%
%ADD23C,.061*%
%ADD39C,.071*%
%ADD28C,.026*%
%AMMACRO37*
4,1,36,.0025,0.0,
.002462,.000434,
.002349,.000855,
.002165,.00125,
.001915,.001607,
.001607,.001915,
.00125,.002165,
.000855,.002349,
.000434,.002462,
0.0,.0025,
-.000434,.002462,
-.000855,.002349,
-.00125,.002165,
-.001607,.001915,
-.001915,.001607,
-.002165,.00125,
-.002349,.000855,
-.002462,.000434,
-.0025,0.0,
-.002462,-.000434,
-.002349,-.000855,
-.002165,-.00125,
-.001915,-.001607,
-.001607,-.001915,
-.00125,-.002165,
-.000855,-.002349,
-.000434,-.002462,
0.0,-.0025,
.000434,-.002462,
.000855,-.002349,
.00125,-.002165,
.001607,-.001915,
.001915,-.001607,
.002165,-.00125,
.002349,-.000855,
.002462,-.000434,
.0025,0.0,
315.*
%
%ADD37MACRO37*%
%AMMACRO22*
4,1,36,.0025,0.0,
.002462,.000434,
.002349,.000855,
.002165,.00125,
.001915,.001607,
.001607,.001915,
.00125,.002165,
.000855,.002349,
.000434,.002462,
0.0,.0025,
-.000434,.002462,
-.000855,.002349,
-.00125,.002165,
-.001607,.001915,
-.001915,.001607,
-.002165,.00125,
-.002349,.000855,
-.002462,.000434,
-.0025,0.0,
-.002462,-.000434,
-.002349,-.000855,
-.002165,-.00125,
-.001915,-.001607,
-.001607,-.001915,
-.00125,-.002165,
-.000855,-.002349,
-.000434,-.002462,
0.0,-.0025,
.000434,-.002462,
.000855,-.002349,
.00125,-.002165,
.001607,-.001915,
.001915,-.001607,
.002165,-.00125,
.002349,-.000855,
.002462,-.000434,
.0025,0.0,
180.*
%
%ADD22MACRO22*%
%AMMACRO14*
4,1,36,.0025,0.0,
.002462,.000434,
.002349,.000855,
.002165,.00125,
.001915,.001607,
.001607,.001915,
.00125,.002165,
.000855,.002349,
.000434,.002462,
0.0,.0025,
-.000434,.002462,
-.000855,.002349,
-.00125,.002165,
-.001607,.001915,
-.001915,.001607,
-.002165,.00125,
-.002349,.000855,
-.002462,.000434,
-.0025,0.0,
-.002462,-.000434,
-.002349,-.000855,
-.002165,-.00125,
-.001915,-.001607,
-.001607,-.001915,
-.00125,-.002165,
-.000855,-.002349,
-.000434,-.002462,
0.0,-.0025,
.000434,-.002462,
.000855,-.002349,
.00125,-.002165,
.001607,-.001915,
.001915,-.001607,
.002165,-.00125,
.002349,-.000855,
.002462,-.000434,
.0025,0.0,
270.*
%
%ADD14MACRO14*%
%AMMACRO41*
4,1,36,.003,0.0,
.002954,.000521,
.002819,.001026,
.002598,.0015,
.002298,.001928,
.001928,.002298,
.0015,.002598,
.001026,.002819,
.000521,.002954,
0.0,.003,
-.000521,.002954,
-.001026,.002819,
-.0015,.002598,
-.001928,.002298,
-.002298,.001928,
-.002598,.0015,
-.002819,.001026,
-.002954,.000521,
-.003,0.0,
-.002954,-.000521,
-.002819,-.001026,
-.002598,-.0015,
-.002298,-.001928,
-.001928,-.002298,
-.0015,-.002598,
-.001026,-.002819,
-.000521,-.002954,
0.0,-.003,
.000521,-.002954,
.001026,-.002819,
.0015,-.002598,
.001928,-.002298,
.002298,-.001928,
.002598,-.0015,
.002819,-.001026,
.002954,-.000521,
.003,0.0,
270.*
%
%ADD41MACRO41*%
%AMMACRO44*
4,1,36,-.003,0.0,
-.002954,.000521,
-.002819,.001026,
-.002598,.0015,
-.002298,.001928,
-.001928,.002298,
-.0015,.002598,
-.001026,.002819,
-.000521,.002954,
0.0,.003,
.000521,.002954,
.001026,.002819,
.0015,.002598,
.001928,.002298,
.002298,.001928,
.002598,.0015,
.002819,.001026,
.002954,.000521,
.003,0.0,
.002954,-.000521,
.002819,-.001026,
.002598,-.0015,
.002298,-.001928,
.001928,-.002298,
.0015,-.002598,
.001026,-.002819,
.000521,-.002954,
0.0,-.003,
-.000521,-.002954,
-.001026,-.002819,
-.0015,-.002598,
-.001928,-.002298,
-.002298,-.001928,
-.002598,-.0015,
-.002819,-.001026,
-.002954,-.000521,
-.003,0.0,
270.*
%
%ADD44MACRO44*%
%ADD40C,.0435*%
%ADD32C,.048*%
%AMMACRO31*
4,1,16,.04562,.02794,
.049779,.019594,
.052425,.010652,
.053478,.001387,
.052906,-.007921,
.050727,-.016987,
.047007,-.025538,
.04562,-.02794,
.0507,-.03302,
.055664,-.023714,
.058936,-.013688,
.060417,-.003246,
.060063,.007295,
.057884,.017614,
.053946,.027397,
.0507,.03302,
.04562,.02794,
90.*
4,1,16,.02794,-.04562,
.019594,-.049779,
.010652,-.052425,
.001387,-.053478,
-.007921,-.052906,
-.016987,-.050727,
-.025538,-.047007,
-.02794,-.04562,
-.03302,-.0507,
-.023714,-.055664,
-.013688,-.058936,
-.003246,-.060417,
.007295,-.060063,
.017614,-.057884,
.027397,-.053946,
.03302,-.0507,
.02794,-.04562,
90.*
4,1,16,-.04562,-.02794,
-.049779,-.019594,
-.052425,-.010652,
-.053478,-.001387,
-.052906,.007921,
-.050727,.016987,
-.047007,.025538,
-.04562,.02794,
-.0507,.03302,
-.055664,.023714,
-.058936,.013688,
-.060417,.003246,
-.060063,-.007295,
-.057884,-.017614,
-.053946,-.027397,
-.0507,-.03302,
-.04562,-.02794,
90.*
4,1,16,-.02794,.04562,
-.019594,.049779,
-.010652,.052425,
-.001387,.053478,
.007921,.052906,
.016987,.050727,
.025538,.047007,
.02794,.04562,
.03302,.0507,
.023714,.055664,
.013688,.058936,
.003246,.060417,
-.007295,.060063,
-.017614,.057884,
-.027397,.053946,
-.03302,.0507,
-.02794,.04562,
90.*
%
%ADD31MACRO31*%
%ADD15C,.066*%
%AMMACRO18*
4,1,14,.06158,.03329,
.066425,.022091,
.069252,.010221,
.069975,-.00196,
.068571,-.014081,
.065084,-.025775,
.06158,-.03329,
.06672,-.03844,
.072381,-.02627,
.075844,-.013302,
.077001,.00007,
.075819,.01344,
.072334,.026402,
.06672,.03844,
.06158,.03329,
0.0*
4,1,14,.03329,-.06158,
.022091,-.066425,
.010221,-.069252,
-.00196,-.069975,
-.014081,-.068571,
-.025775,-.065084,
-.03329,-.06158,
-.03844,-.06672,
-.02627,-.072381,
-.013302,-.075844,
.00007,-.077001,
.01344,-.075819,
.026402,-.072334,
.03844,-.06672,
.03329,-.06158,
0.0*
4,1,14,-.06158,-.03329,
-.066425,-.022091,
-.069252,-.010221,
-.069975,.00196,
-.068571,.014081,
-.065084,.025775,
-.06158,.03329,
-.06672,.03844,
-.072381,.02627,
-.075844,.013302,
-.077001,-.00007,
-.075819,-.01344,
-.072334,-.026402,
-.06672,-.03844,
-.06158,-.03329,
0.0*
4,1,14,-.03329,.06158,
-.022091,.066425,
-.010221,.069252,
.00196,.069975,
.014081,.068571,
.025775,.065084,
.03329,.06158,
.03844,.06672,
.02627,.072381,
.013302,.075844,
-.00007,.077001,
-.01344,.075819,
-.026402,.072334,
-.03844,.06672,
-.03329,.06158,
0.0*
%
%ADD18MACRO18*%
%AMMACRO36*
4,1,15,.06525,.03697,
.070678,.025078,
.073959,.012424,
.074993,-.000608,
.073748,-.013621,
.070263,-.026221,
.06525,-.03697,
.07037,-.04209,
.07661,-.029231,
.080522,-.015484,
.081987,-.001266,
.080961,.01299,
.077476,.026852,
.071636,.039897,
.07037,.04209,
.06525,.03697,
0.0*
4,1,15,.03697,-.06525,
.025078,-.070678,
.012424,-.073959,
-.000608,-.074993,
-.013621,-.073748,
-.026221,-.070263,
-.03697,-.06525,
-.04209,-.07037,
-.029231,-.07661,
-.015484,-.080522,
-.001266,-.081987,
.01299,-.080961,
.026852,-.077476,
.039897,-.071636,
.04209,-.07037,
.03697,-.06525,
0.0*
4,1,15,-.06525,-.03697,
-.070678,-.025078,
-.073959,-.012424,
-.074993,.000608,
-.073748,.013621,
-.070263,.026221,
-.06525,.03697,
-.07037,.04209,
-.07661,.029231,
-.080522,.015484,
-.081987,.001266,
-.080961,-.01299,
-.077476,-.026852,
-.071636,-.039897,
-.07037,-.04209,
-.06525,-.03697,
0.0*
4,1,15,-.03697,.06525,
-.025078,.070678,
-.012424,.073959,
.000608,.074993,
.013621,.073748,
.026221,.070263,
.03697,.06525,
.04209,.07037,
.029231,.07661,
.015484,.080522,
.001266,.081987,
-.01299,.080961,
-.026852,.077476,
-.039897,.071636,
-.04209,.07037,
-.03697,.06525,
0.0*
%
%ADD36MACRO36*%
%ADD26C,.078*%
%ADD11C,.087*%
%ADD33C,.097*%
%AMMACRO17*
4,1,15,.06231,.03403,
.067273,.022693,
.070191,.010666,
.070977,-.001684,
.069606,-.013984,
.066121,-.025858,
.06231,-.03403,
.06745,-.03917,
.073227,-.026862,
.076779,-.013739,
.077998,-.000197,
.076848,.01335,
.073362,.026492,
.067647,.038828,
.06745,.03917,
.06231,.03403,
0.0*
4,1,15,.03403,-.06231,
.022693,-.067273,
.010666,-.070191,
-.001684,-.070977,
-.013984,-.069606,
-.025858,-.066121,
-.03403,-.06231,
-.03917,-.06745,
-.026862,-.073227,
-.013739,-.076779,
-.000197,-.077998,
.01335,-.076848,
.026492,-.073362,
.038828,-.067647,
.03917,-.06745,
.03403,-.06231,
0.0*
4,1,15,-.06231,-.03403,
-.067273,-.022693,
-.070191,-.010666,
-.070977,.001684,
-.069606,.013984,
-.066121,.025858,
-.06231,.03403,
-.06745,.03917,
-.073227,.026862,
-.076779,.013739,
-.077998,.000197,
-.076848,-.01335,
-.073362,-.026492,
-.067647,-.038828,
-.06745,-.03917,
-.06231,-.03403,
0.0*
4,1,15,-.03403,.06231,
-.022693,.067273,
-.010666,.070191,
.001684,.070977,
.013984,.069606,
.025858,.066121,
.03403,.06231,
.03917,.06745,
.026862,.073227,
.013739,.076779,
.000197,.077998,
-.01335,.076848,
-.026492,.073362,
-.038828,.067647,
-.03917,.06745,
-.03403,.06231,
0.0*
%
%ADD17MACRO17*%
%AMMACRO30*
4,1,16,.0711,.04282,
.077455,.029823,
.081457,.01592,
.082984,.001533,
.08199,-.0129,
.078504,-.026942,
.072633,-.040164,
.0711,-.04282,
.07619,-.04791,
.083352,-.033952,
.087981,-.018962,
.089937,-.003396,
.089161,.012273,
.085675,.027569,
.079586,.042027,
.07619,.04791,
.0711,.04282,
0.0*
4,1,16,.04282,-.0711,
.029823,-.077455,
.01592,-.081457,
.001533,-.082984,
-.0129,-.08199,
-.026942,-.078504,
-.040164,-.072633,
-.04282,-.0711,
-.04791,-.07619,
-.033952,-.083352,
-.018962,-.087981,
-.003396,-.089937,
.012273,-.089161,
.027569,-.085675,
.042027,-.079586,
.04791,-.07619,
.04282,-.0711,
0.0*
4,1,16,-.0711,-.04282,
-.077455,-.029823,
-.081457,-.01592,
-.082984,-.001533,
-.08199,.0129,
-.078504,.026942,
-.072633,.040164,
-.0711,.04282,
-.07619,.04791,
-.083352,.033952,
-.087981,.018962,
-.089937,.003396,
-.089161,-.012273,
-.085675,-.027569,
-.079586,-.042027,
-.07619,-.04791,
-.0711,-.04282,
0.0*
4,1,16,-.04282,.0711,
-.029823,.077455,
-.01592,.081457,
-.001533,.082984,
.0129,.08199,
.026942,.078504,
.040164,.072633,
.04282,.0711,
.04791,.07619,
.033952,.083352,
.018962,.087981,
.003396,.089937,
-.012273,.089161,
-.027569,.085675,
-.042027,.079586,
-.04791,.07619,
-.04282,.0711,
0.0*
%
%ADD30MACRO30*%
%AMMACRO35*
4,1,15,.02142,.01082,
.022973,.006936,
.023829,.002841,
.02396,-.00134,
.023364,-.00548,
.022057,-.009454,
.02142,-.01082,
.02657,-.01597,
.02894,-.011114,
.03043,-.005919,
.030995,-.000545,
.030619,.004845,
.029313,.010088,
.027115,.015025,
.02657,.01597,
.02142,.01082,
0.0*
4,1,15,.01082,-.02142,
.006936,-.022973,
.002841,-.023829,
-.00134,-.02396,
-.00548,-.023364,
-.009454,-.022057,
-.01082,-.02142,
-.01597,-.02657,
-.011114,-.02894,
-.005919,-.03043,
-.000545,-.030995,
.004845,-.030619,
.010088,-.029313,
.015025,-.027115,
.01597,-.02657,
.01082,-.02142,
0.0*
4,1,15,-.02142,-.01082,
-.022973,-.006936,
-.023829,-.002841,
-.02396,.00134,
-.023364,.00548,
-.022057,.009454,
-.02142,.01082,
-.02657,.01597,
-.02894,.011114,
-.03043,.005919,
-.030995,.000545,
-.030619,-.004845,
-.029313,-.010088,
-.027115,-.015025,
-.02657,-.01597,
-.02142,-.01082,
0.0*
4,1,15,-.01082,.02142,
-.006936,.022973,
-.002841,.023829,
.00134,.02396,
.00548,.023364,
.009454,.022057,
.01082,.02142,
.01597,.02657,
.011114,.02894,
.005919,.03043,
.000545,.030995,
-.004845,.030619,
-.010088,.029313,
-.015025,.027115,
-.01597,.02657,
-.01082,.02142,
0.0*
%
%ADD35MACRO35*%
%AMMACRO34*
4,1,15,.01993,.00932,
.021246,.005718,
.021916,.001941,
.02192,-.001894,
.021258,-.005671,
.01995,-.009276,
.01993,-.00932,
.02511,-.01451,
.027248,-.009929,
.028558,-.005047,
.029001,-.000011,
.028562,.005025,
.027256,.009909,
.025121,.014491,
.02511,.01451,
.01993,.00932,
90.*
4,1,15,.00932,-.01993,
.005718,-.021246,
.001941,-.021916,
-.001894,-.02192,
-.005671,-.021258,
-.009276,-.01995,
-.00932,-.01993,
-.01451,-.02511,
-.009929,-.027248,
-.005047,-.028558,
-.000011,-.029001,
.005025,-.028562,
.009909,-.027256,
.014491,-.025121,
.01451,-.02511,
.00932,-.01993,
90.*
4,1,15,-.01993,-.00932,
-.021246,-.005718,
-.021916,-.001941,
-.02192,.001894,
-.021258,.005671,
-.01995,.009276,
-.01993,.00932,
-.02511,.01451,
-.027248,.009929,
-.028558,.005047,
-.029001,.000011,
-.028562,-.005025,
-.027256,-.009909,
-.025121,-.014491,
-.02511,-.01451,
-.01993,-.00932,
90.*
4,1,15,-.00932,.01993,
-.005718,.021246,
-.001941,.021916,
.001894,.02192,
.005671,.021258,
.009276,.01995,
.00932,.01993,
.01451,.02511,
.009929,.027248,
.005047,.028558,
.000011,.029001,
-.005025,.028562,
-.009909,.027256,
-.014491,.025121,
-.01451,.02511,
-.00932,.01993,
90.*
%
%ADD34MACRO34*%
%AMMACRO24*
4,1,15,.02475,.01414,
.026829,.009627,
.028094,.004822,
.028504,-.000129,
.028049,-.005077,
.026741,-.009871,
.02475,-.01414,
.02984,-.01923,
.032726,-.013756,
.034617,-.007864,
.035457,-.001734,
.03522,.00445,
.033912,.010498,
.031574,.016227,
.02984,.01923,
.02475,.01414,
0.0*
4,1,15,.01414,-.02475,
.009627,-.026829,
.004822,-.028094,
-.000129,-.028504,
-.005077,-.028049,
-.009871,-.026741,
-.01414,-.02475,
-.01923,-.02984,
-.013756,-.032726,
-.007864,-.034617,
-.001734,-.035457,
.00445,-.03522,
.010498,-.033912,
.016227,-.031574,
.01923,-.02984,
.01414,-.02475,
0.0*
4,1,15,-.02475,-.01414,
-.026829,-.009627,
-.028094,-.004822,
-.028504,.000129,
-.028049,.005077,
-.026741,.009871,
-.02475,.01414,
-.02984,.01923,
-.032726,.013756,
-.034617,.007864,
-.035457,.001734,
-.03522,-.00445,
-.033912,-.010498,
-.031574,-.016227,
-.02984,-.01923,
-.02475,-.01414,
0.0*
4,1,15,-.01414,.02475,
-.009627,.026829,
-.004822,.028094,
.000129,.028504,
.005077,.028049,
.009871,.026741,
.01414,.02475,
.01923,.02984,
.013756,.032726,
.007864,.034617,
.001734,.035457,
-.00445,.03522,
-.010498,.033912,
-.016227,.031574,
-.01923,.02984,
-.01414,.02475,
0.0*
%
%ADD24MACRO24*%
%AMMACRO10*
4,1,15,.03682,.01914,
.039584,.012455,
.041146,.005393,
.041457,-.001834,
.040509,-.009005,
.03833,-.015903,
.03682,-.01914,
.04197,-.0243,
.045552,-.016643,
.04775,-.00848,
.048497,-.000059,
.047771,.008363,
.045593,.016531,
.042029,.024197,
.04197,.0243,
.03682,.01914,
0.0*
4,1,15,.01914,-.03682,
.012455,-.039584,
.005393,-.041146,
-.001834,-.041457,
-.009005,-.040509,
-.015903,-.03833,
-.01914,-.03682,
-.0243,-.04197,
-.016643,-.045552,
-.00848,-.04775,
-.000059,-.048497,
.008363,-.047771,
.016531,-.045593,
.024197,-.042029,
.0243,-.04197,
.01914,-.03682,
0.0*
4,1,15,-.03682,-.01914,
-.039584,-.012455,
-.041146,-.005393,
-.041457,.001834,
-.040509,.009005,
-.03833,.015903,
-.03682,.01914,
-.04197,.0243,
-.045552,.016643,
-.04775,.00848,
-.048497,.000059,
-.047771,-.008363,
-.045593,-.016531,
-.042029,-.024197,
-.04197,-.0243,
-.03682,-.01914,
0.0*
4,1,15,-.01914,.03682,
-.012455,.039584,
-.005393,.041146,
.001834,.041457,
.009005,.040509,
.015903,.03833,
.01914,.03682,
.0243,.04197,
.016643,.045552,
.00848,.04775,
.000059,.048497,
-.008363,.047771,
-.016531,.045593,
-.024197,.042029,
-.0243,.04197,
-.01914,.03682,
0.0*
%
%ADD10MACRO10*%
%ADD29O,.156X.219*%
%ADD21C,.155*%
%AMMACRO38*
4,1,36,.0025,0.0,
.002462,.000434,
.002349,.000855,
.002165,.00125,
.001915,.001607,
.001607,.001915,
.00125,.002165,
.000855,.002349,
.000434,.002462,
0.0,.0025,
-.000434,.002462,
-.000855,.002349,
-.00125,.002165,
-.001607,.001915,
-.001915,.001607,
-.002165,.00125,
-.002349,.000855,
-.002462,.000434,
-.0025,0.0,
-.002462,-.000434,
-.002349,-.000855,
-.002165,-.00125,
-.001915,-.001607,
-.001607,-.001915,
-.00125,-.002165,
-.000855,-.002349,
-.000434,-.002462,
0.0,-.0025,
.000434,-.002462,
.000855,-.002349,
.00125,-.002165,
.001607,-.001915,
.001915,-.001607,
.002165,-.00125,
.002349,-.000855,
.002462,-.000434,
.0025,0.0,
45.*
%
%ADD38MACRO38*%
%AMMACRO20*
4,1,36,.0025,0.0,
.002462,.000434,
.002349,.000855,
.002165,.00125,
.001915,.001607,
.001607,.001915,
.00125,.002165,
.000855,.002349,
.000434,.002462,
0.0,.0025,
-.000434,.002462,
-.000855,.002349,
-.00125,.002165,
-.001607,.001915,
-.001915,.001607,
-.002165,.00125,
-.002349,.000855,
-.002462,.000434,
-.0025,0.0,
-.002462,-.000434,
-.002349,-.000855,
-.002165,-.00125,
-.001915,-.001607,
-.001607,-.001915,
-.00125,-.002165,
-.000855,-.002349,
-.000434,-.002462,
0.0,-.0025,
.000434,-.002462,
.000855,-.002349,
.00125,-.002165,
.001607,-.001915,
.001915,-.001607,
.002165,-.00125,
.002349,-.000855,
.002462,-.000434,
.0025,0.0,
90.*
%
%ADD20MACRO20*%
%AMMACRO42*
4,1,36,.003,0.0,
.002954,.000521,
.002819,.001026,
.002598,.0015,
.002298,.001928,
.001928,.002298,
.0015,.002598,
.001026,.002819,
.000521,.002954,
0.0,.003,
-.000521,.002954,
-.001026,.002819,
-.0015,.002598,
-.001928,.002298,
-.002298,.001928,
-.002598,.0015,
-.002819,.001026,
-.002954,.000521,
-.003,0.0,
-.002954,-.000521,
-.002819,-.001026,
-.002598,-.0015,
-.002298,-.001928,
-.001928,-.002298,
-.0015,-.002598,
-.001026,-.002819,
-.000521,-.002954,
0.0,-.003,
.000521,-.002954,
.001026,-.002819,
.0015,-.002598,
.001928,-.002298,
.002298,-.001928,
.002598,-.0015,
.002819,-.001026,
.002954,-.000521,
.003,0.0,
90.*
%
%ADD42MACRO42*%
%AMMACRO16*
4,1,36,.0025,0.0,
.002462,.000434,
.002349,.000855,
.002165,.00125,
.001915,.001607,
.001607,.001915,
.00125,.002165,
.000855,.002349,
.000434,.002462,
0.0,.0025,
-.000434,.002462,
-.000855,.002349,
-.00125,.002165,
-.001607,.001915,
-.001915,.001607,
-.002165,.00125,
-.002349,.000855,
-.002462,.000434,
-.0025,0.0,
-.002462,-.000434,
-.002349,-.000855,
-.002165,-.00125,
-.001915,-.001607,
-.001607,-.001915,
-.00125,-.002165,
-.000855,-.002349,
-.000434,-.002462,
0.0,-.0025,
.000434,-.002462,
.000855,-.002349,
.00125,-.002165,
.001607,-.001915,
.001915,-.001607,
.002165,-.00125,
.002349,-.000855,
.002462,-.000434,
.0025,0.0,
0.0*
%
%ADD16MACRO16*%
%AMMACRO43*
4,1,36,-.003,0.0,
-.002954,.000521,
-.002819,.001026,
-.002598,.0015,
-.002298,.001928,
-.001928,.002298,
-.0015,.002598,
-.001026,.002819,
-.000521,.002954,
0.0,.003,
.000521,.002954,
.001026,.002819,
.0015,.002598,
.001928,.002298,
.002298,.001928,
.002598,.0015,
.002819,.001026,
.002954,.000521,
.003,0.0,
.002954,-.000521,
.002819,-.001026,
.002598,-.0015,
.002298,-.001928,
.001928,-.002298,
.0015,-.002598,
.001026,-.002819,
.000521,-.002954,
0.0,-.003,
-.000521,-.002954,
-.001026,-.002819,
-.0015,-.002598,
-.001928,-.002298,
-.002298,-.001928,
-.002598,-.0015,
-.002819,-.001026,
-.002954,-.000521,
-.003,0.0,
90.*
%
%ADD43MACRO43*%
%AMMACRO27*
4,1,36,.0025,0.0,
.002462,.000434,
.002349,.000855,
.002165,.00125,
.001915,.001607,
.001607,.001915,
.00125,.002165,
.000855,.002349,
.000434,.002462,
0.0,.0025,
-.000434,.002462,
-.000855,.002349,
-.00125,.002165,
-.001607,.001915,
-.001915,.001607,
-.002165,.00125,
-.002349,.000855,
-.002462,.000434,
-.0025,0.0,
-.002462,-.000434,
-.002349,-.000855,
-.002165,-.00125,
-.001915,-.001607,
-.001607,-.001915,
-.00125,-.002165,
-.000855,-.002349,
-.000434,-.002462,
0.0,-.0025,
.000434,-.002462,
.000855,-.002349,
.00125,-.002165,
.001607,-.001915,
.001915,-.001607,
.002165,-.00125,
.002349,-.000855,
.002462,-.000434,
.0025,0.0,
84.*
%
%ADD27MACRO27*%
%AMMACRO13*
4,1,15,.03682,.01914,
.039584,.012455,
.041146,.005393,
.041457,-.001834,
.040509,-.009005,
.03833,-.015903,
.03682,-.01914,
.04197,-.0243,
.045552,-.016643,
.04775,-.00848,
.048497,-.000059,
.047771,.008363,
.045593,.016531,
.042029,.024197,
.04197,.0243,
.03682,.01914,
180.*
4,1,15,.01914,-.03682,
.012455,-.039584,
.005393,-.041146,
-.001834,-.041457,
-.009005,-.040509,
-.015903,-.03833,
-.01914,-.03682,
-.0243,-.04197,
-.016643,-.045552,
-.00848,-.04775,
-.000059,-.048497,
.008363,-.047771,
.016531,-.045593,
.024197,-.042029,
.0243,-.04197,
.01914,-.03682,
180.*
4,1,15,-.03682,-.01914,
-.039584,-.012455,
-.041146,-.005393,
-.041457,.001834,
-.040509,.009005,
-.03833,.015903,
-.03682,.01914,
-.04197,.0243,
-.045552,.016643,
-.04775,.00848,
-.048497,.000059,
-.047771,-.008363,
-.045593,-.016531,
-.042029,-.024197,
-.04197,-.0243,
-.03682,-.01914,
180.*
4,1,15,-.01914,.03682,
-.012455,.039584,
-.005393,.041146,
.001834,.041457,
.009005,.040509,
.015903,.03833,
.01914,.03682,
.0243,.04197,
.016643,.045552,
.00848,.04775,
.000059,.048497,
-.008363,.047771,
-.016531,.045593,
-.024197,.042029,
-.0243,.04197,
-.01914,.03682,
180.*
%
%ADD13MACRO13*%
%AMMACRO12*
4,1,15,-.03682,.01914,
-.039584,.012455,
-.041146,.005393,
-.041457,-.001834,
-.040509,-.009005,
-.03833,-.015903,
-.03682,-.01914,
-.04197,-.0243,
-.045552,-.016643,
-.04775,-.00848,
-.048497,-.000059,
-.047771,.008363,
-.045593,.016531,
-.042029,.024197,
-.04197,.0243,
-.03682,.01914,
180.*
4,1,15,-.01914,-.03682,
-.012455,-.039584,
-.005393,-.041146,
.001834,-.041457,
.009005,-.040509,
.015903,-.03833,
.01914,-.03682,
.0243,-.04197,
.016643,-.045552,
.00848,-.04775,
.000059,-.048497,
-.008363,-.047771,
-.016531,-.045593,
-.024197,-.042029,
-.0243,-.04197,
-.01914,-.03682,
180.*
4,1,15,.03682,-.01914,
.039584,-.012455,
.041146,-.005393,
.041457,.001834,
.040509,.009005,
.03833,.015903,
.03682,.01914,
.04197,.0243,
.045552,.016643,
.04775,.00848,
.048497,.000059,
.047771,-.008363,
.045593,-.016531,
.042029,-.024197,
.04197,-.0243,
.03682,-.01914,
180.*
4,1,15,.01914,.03682,
.012455,.039584,
.005393,.041146,
-.001834,.041457,
-.009005,.040509,
-.015903,.03833,
-.01914,.03682,
-.0243,.04197,
-.016643,.045552,
-.00848,.04775,
-.000059,.048497,
.008363,.047771,
.016531,.045593,
.024197,.042029,
.0243,.04197,
.01914,.03682,
180.*
%
%ADD12MACRO12*%
%ADD45C,.006*%
%ADD56C,.07306*%
%ADD51C,.08008*%
%ADD47C,.06807*%
%ADD53C,.06809*%
%ADD52C,.09908*%
%ADD54R,.01102X.02604*%
%ADD55R,.01104X.02604*%
%ADD49O,.03004X.06504*%
%ADD50O,.03006X.06506*%
%ADD46C,.16506*%
%ADD57R,.04924X.03014*%
%ADD48O,.2363X.2993*%
G75*
%LPD*%
G75*
G36*
G01X-407000Y-793716D02*
X2010999D01*
Y1475775D01*
X-407000D01*
Y-793716D01*
G37*
%LPC*%
G75*
G36*
G01X-15748Y472016D02*
G02X-9874Y466142I0J-5874D01*
G01Y25945D01*
G02X-15748Y20071I-5874J0D01*
G01X-70000D01*
G02X-75874Y25945I0J5874D01*
G01Y466142D01*
G02X-70000Y472016I5874J0D01*
G01X-15748D01*
G37*
G36*
G01X2004Y336650D02*
Y442126D01*
G02X7874Y447996I5870J0D01*
G01X17717D01*
G03X21689Y451968I-1J3973D01*
G01Y467369D01*
X22132Y467812D01*
X23372D01*
X23781Y467404D01*
X38207D01*
X38828Y468024D01*
X40009D01*
X40378Y467655D01*
Y451968D01*
G03X44350Y447996I3973J1D01*
G01X50256D01*
G03X54228Y451968I-1J3973D01*
G01Y462100D01*
X122504D01*
Y451870D01*
G03X137339I7418J0D01*
G01Y462100D01*
X172543D01*
Y450098D01*
G03X183835I5646J0D01*
G01Y462100D01*
X252071D01*
Y450886D01*
G03X264937I6433J0D01*
G01Y462100D01*
X300122D01*
Y451968D01*
G03X304094Y447996I3973J1D01*
G01X310000D01*
G03X313973Y451969I0J3973D01*
G01Y467400D01*
X314385Y467812D01*
X315625D01*
X316034Y467404D01*
X330460D01*
X331081Y468024D01*
X332262D01*
X332642Y467644D01*
Y451968D01*
G03X336614Y447996I3973J1D01*
G01X346457D01*
G02X352327Y442126I0J-5870D01*
G01Y336650D01*
X345472D01*
G03X341500Y332678I0J-3973D01*
G01Y322834D01*
G03X345472Y318862I3972J0D01*
G01X352327D01*
Y271930D01*
X352331Y271926D01*
Y266763D01*
X352327Y266759D01*
Y7874D01*
G02X346457Y2004I-5870J0D01*
G01X7874D01*
G02X2004Y7874I0J5870D01*
G01Y242282D01*
X2000Y242286D01*
Y247986D01*
X2004Y247990D01*
Y318862D01*
X8858D01*
G03X12831Y322835I0J3973D01*
G01Y332677D01*
G03X8858Y336650I-3973J0D01*
G01X2004D01*
G37*
G36*
G01X482252Y-509842D02*
G02X476378Y-515716I-5874J0D01*
G01X370079D01*
G02X364205Y-509842I0J5874D01*
G01Y466142D01*
G02X370079Y472016I5874J0D01*
G01X476378D01*
G02X482252Y466142I0J-5874D01*
G01Y-509842D01*
G37*
%LPD*%
G75*
G36*
G01X242870Y239000D02*
G02X243872Y238580I0J-1405D01*
G02Y236612I-853J-984D01*
G02X242870Y236192I-1002J985D01*
G02X242378Y236281I0J1404D01*
G01X242344Y236294D01*
X240395D01*
G02X239870Y236192I-525J1302D01*
G02Y239000I0J1404D01*
G02X240395Y238898I0J-1404D01*
G01X242344D01*
X242378Y238911D01*
G02X242870Y239000I492J-1315D01*
G37*
G36*
G01X239998Y225853D02*
Y229002D01*
G02X242602I1302J0D01*
G01Y226194D01*
G02X242638Y225890I-1264J-304D01*
G02X242261Y224974I-1301J0D01*
G02X241300Y224551I-961J880D01*
G02X239998Y225853I0J1302D01*
G37*
G36*
G01X250749Y236604D02*
X253898D01*
G02Y233998I0J-1303D01*
G01X250749D01*
G02Y236604I0J1303D01*
G37*
G36*
G01X253898Y233454D02*
X257047D01*
G02Y230848I0J-1303D01*
G01X253898D01*
G02Y233454I0J1303D01*
G37*
G36*
G01X181514Y379113D02*
Y379668D01*
X181750D01*
Y380710D01*
X183250D01*
Y379668D01*
X183486D01*
Y379113D01*
G02X183092Y378722I-391J0D01*
G01X181908D01*
G02X181514Y379113I-3J391D01*
G37*
G36*
G01X177514D02*
Y379668D01*
X177750D01*
Y380710D01*
X179250D01*
Y379668D01*
X179486D01*
Y379113D01*
G02X179092Y378722I-391J0D01*
G01X177908D01*
G02X177514Y379113I-3J391D01*
G37*
G36*
G01X179486Y383287D02*
Y382732D01*
X179250D01*
Y381690D01*
X177750D01*
Y382732D01*
X177514D01*
Y383287D01*
G02X177908Y383678I391J0D01*
G01X179092D01*
G02X179486Y383287I3J-391D01*
G37*
G36*
G01X153237Y61386D02*
X161111D01*
G02Y55780I0J-2803D01*
G01X153237D01*
G02Y61386I0J2803D01*
G37*
G36*
G01X165048Y55480D02*
X172922D01*
G02Y49874I0J-2803D01*
G01X165048D01*
G02Y55480I0J2803D01*
G37*
G36*
G01X176859Y61386D02*
X184733D01*
G02Y55780I0J-2803D01*
G01X176859D01*
G02Y61386I0J2803D01*
G37*
G36*
G01X244450Y233454D02*
X247599D01*
G02Y230848I0J-1303D01*
G01X244450D01*
G02Y233454I0J1303D01*
G37*
G36*
G01X250749Y230304D02*
X253898D01*
G02Y227700I0J-1302D01*
G01X250749D01*
G02Y230304I0J1302D01*
G37*
G36*
G01X162550Y385832D02*
X159050D01*
G02Y388836I0J1502D01*
G01X162550D01*
G02Y385832I0J-1502D01*
G37*
G36*
G01X72150Y425702D02*
X75650D01*
G02Y422696I0J-1503D01*
G01X72150D01*
G02Y425702I0J1503D01*
G37*
G36*
G01X92801Y454296D02*
X96301D01*
G02Y451290I0J-1503D01*
G01X92801D01*
G02Y454296I0J1503D01*
G37*
G36*
G01X60622Y432776D02*
X64122D01*
G02Y429770I0J-1503D01*
G01X60622D01*
G02Y432776I0J1503D01*
G37*
G36*
G01X182350Y384132D02*
X178850D01*
G02Y387136I0J1502D01*
G01X182350D01*
G02Y384132I0J-1502D01*
G37*
G36*
G01X216725Y440718D02*
X213225D01*
G02Y443722I0J1502D01*
G01X216725D01*
G02Y440718I0J-1502D01*
G37*
G36*
G01X159923Y97784D02*
X163423D01*
G02Y94778I0J-1503D01*
G01X159923D01*
G02Y97784I0J1503D01*
G37*
G36*
G01X169347D02*
X172847D01*
G02Y94778I0J-1503D01*
G01X169347D01*
G02Y97784I0J1503D01*
G37*
G36*
G01X221225Y408648D02*
X217725D01*
G02Y411652I0J1502D01*
G01X221225D01*
G02Y408648I0J-1502D01*
G37*
G36*
G01X183486Y383287D02*
Y382732D01*
X183250D01*
Y381690D01*
X181750D01*
Y382732D01*
X181514D01*
Y383287D01*
G02X181908Y383678I391J0D01*
G01X183092D01*
G02X183486Y383287I3J-391D01*
G37*
G36*
G01X267722Y175288D02*
X264222D01*
G02Y178294I0J1503D01*
G01X267722D01*
G02Y175288I0J-1503D01*
G37*
G36*
G01X247416Y246126D02*
Y245572D01*
X247180D01*
Y244528D01*
X245680D01*
Y245572D01*
X245444D01*
Y246126D01*
G02X245838Y246517I391J0D01*
G01X245839Y246516D01*
X247021D01*
X247022Y246517D01*
G02X247416Y246126I3J-391D01*
G37*
G36*
G01X243416D02*
Y245572D01*
X243180D01*
Y244528D01*
X241680D01*
Y245572D01*
X241444D01*
Y246126D01*
G02X241838Y246517I391J0D01*
G01X241839Y246516D01*
X243021D01*
X243022Y246517D01*
G02X243416Y246126I3J-391D01*
G37*
G36*
G01X241444Y241952D02*
Y242506D01*
X241680D01*
Y243550D01*
X243180D01*
Y242506D01*
X243416D01*
Y241952D01*
G02X243022Y241561I-391J0D01*
G01X243021Y241562D01*
X241839D01*
X241838Y241561D01*
G02X241444Y241952I-3J391D01*
G37*
G36*
G01X245444D02*
Y242506D01*
X245680D01*
Y243550D01*
X247180D01*
Y242506D01*
X247416D01*
Y241952D01*
G02X247022Y241561I-391J0D01*
G01X247021Y241562D01*
X245839D01*
X245838Y241561D01*
G02X245444Y241952I-3J391D01*
G37*
G36*
G01X81990Y449588D02*
X85490D01*
G02Y446582I0J-1503D01*
G01X81990D01*
G02Y449588I0J1503D01*
G37*
G36*
G01X52750Y425702D02*
X56250D01*
G02Y422698I0J-1502D01*
G01X52750D01*
G02Y425702I0J1502D01*
G37*
G36*
G01X255213Y107602D02*
X258713D01*
G02Y104596I0J-1503D01*
G01X255213D01*
G02Y107602I0J1503D01*
G37*
G36*
G01X246488Y107294D02*
X249988D01*
G02Y104290I0J-1502D01*
G01X246488D01*
G02Y107294I0J1502D01*
G37*
G36*
G01X266080Y205760D02*
X262580D01*
G02Y208764I0J1502D01*
G01X266080D01*
G02Y205760I0J-1502D01*
G37*
G36*
G01X267080Y213090D02*
X263580D01*
G02Y216096I0J1503D01*
G01X267080D01*
G02Y213090I0J-1503D01*
G37*
G36*
G01X95870Y446986D02*
X99370D01*
G02Y443980I0J-1503D01*
G01X95870D01*
G02Y446986I0J1503D01*
G37*
G36*
G01X375152Y-442590D02*
Y-439446D01*
G02X374402Y-438145I753J1301D01*
G02X375904Y-436642I1502J1D01*
G01X379304D01*
G02X380806Y-438145I-1J-1503D01*
G02X380076Y-439434I-1503J0D01*
G01Y-442590D01*
X375152D01*
G37*
G36*
G01X397080Y-122524D02*
G02X395578Y-121021I1J1503D01*
G02X396308Y-119732I1503J0D01*
G01Y-116576D01*
X401232D01*
Y-119720D01*
G02X401982Y-121021I-753J-1301D01*
G02X400480Y-122524I-1502J-1D01*
G01X397080D01*
G37*
G36*
G01X375964Y-217462D02*
G02X374462Y-215959I1J1503D01*
G02X375192Y-214670I1503J0D01*
G01Y-211514D01*
X380116D01*
Y-214658D01*
G02X380866Y-215959I-753J-1301D01*
G02X379364Y-217462I-1502J-1D01*
G01X375964D01*
G37*
G36*
G01X375876Y-161376D02*
G02Y-158370I0J1503D01*
G01X379276D01*
G02Y-161376I0J-1503D01*
G01X375876D01*
G37*
G36*
G01X375964Y10810D02*
G02Y13816I0J1503D01*
G01X379364D01*
G02Y10810I0J-1503D01*
G01X375964D01*
G37*
G36*
G01X375904Y66896D02*
G02Y69902I0J1503D01*
G01X379304D01*
G02Y66896I0J-1503D01*
G01X375904D01*
G37*
G36*
G01X375964Y380082D02*
G02Y383088I0J1503D01*
G01X379364D01*
G02Y380082I0J-1503D01*
G01X375964D01*
G37*
G36*
G01X396240Y-468652D02*
Y-465508D01*
G02X395490Y-464207I753J1301D01*
G02X396992Y-462704I1502J1D01*
G01X400392D01*
G02X401894Y-464207I-1J-1503D01*
G02X401164Y-465496I-1503J0D01*
G01Y-468652D01*
X396240D01*
G37*
G54D56*
X403692Y-481375D03*
X393692D03*
Y-456375D03*
X403692D03*
X382604Y-455313D03*
X372604D03*
Y-430313D03*
X382604D03*
X382664Y373753D03*
X372664D03*
Y398753D03*
X382664D03*
X393750Y272050D03*
X403750D03*
Y247050D03*
X393750D03*
Y200538D03*
X403750D03*
Y225538D03*
X393750D03*
X393780Y-128853D03*
X403780D03*
Y-103853D03*
X393780D03*
X403750Y-57222D03*
X393750D03*
Y-82222D03*
X403750D03*
X372604Y76231D03*
X382604D03*
Y51231D03*
X372604D03*
X413750Y-57222D03*
Y-82222D03*
X382664Y4481D03*
X372664D03*
Y29481D03*
X382664D03*
X403750Y398810D03*
X413750D03*
Y423810D03*
X403750D03*
X413750Y200538D03*
Y225538D03*
Y272050D03*
Y247050D03*
X372664Y-223791D03*
X382664D03*
Y-198791D03*
X372664D03*
X393750Y398810D03*
Y423810D03*
X372576Y-152041D03*
X382576D03*
Y-177041D03*
X372576D03*
G54D51*
X65945Y297776D03*
G54D47*
X45276Y18465D03*
X17716D03*
X264173Y20040D03*
X291733D03*
G54D53*
X309055Y18465D03*
X336615D03*
G54D52*
X144685Y297776D03*
G54D54*
X166063Y368500D03*
X160157Y359838D03*
X158189D03*
X168031Y368500D03*
X166063Y359838D03*
X168031D03*
G54D55*
X170000Y368500D03*
X164094D03*
G54D49*
X56482Y455094D03*
X102190Y64975D03*
G54D50*
X63569Y455094D03*
G54D46*
X-58189Y454331D03*
X340639Y432809D03*
X27300Y68200D03*
X464567Y-498031D03*
Y454331D03*
G54D57*
X398740Y211309D03*
X408740Y409581D03*
X398760Y-67993D03*
X408760Y261279D03*
G54D48*
X105315Y186571D03*
G54D19*
X19200Y102700D03*
X12500Y102000D03*
X19100Y187420D03*
X15922Y224568D03*
Y227168D03*
X18422Y224568D03*
Y227168D03*
X17065Y255712D03*
X13736Y299891D03*
Y303280D03*
X13869Y352239D03*
X14000Y401700D03*
Y406700D03*
Y404200D03*
X17700Y427600D03*
X14600Y422500D03*
X14700Y425000D03*
X25200Y116300D03*
X31890Y110400D03*
X23736Y127758D03*
Y130758D03*
X32236Y127758D03*
Y130758D03*
X21000Y227000D03*
Y224500D03*
X24705Y258767D03*
X22237Y304626D03*
X30638Y304602D03*
X22237Y301237D03*
X30638Y301213D03*
X30700Y315500D03*
X33000Y318700D03*
X23810Y322534D03*
X31300Y329900D03*
X31000Y342500D03*
X26300Y374400D03*
X36200Y368400D03*
X31600Y379600D03*
X32700Y395381D03*
X20600Y428900D03*
X25202Y425329D03*
X29400Y430900D03*
X23677Y422419D03*
X31500Y428500D03*
X32100Y432800D03*
X45500Y41500D03*
X35304Y58317D03*
X45500Y92500D03*
X40340Y100710D03*
X45001Y95144D03*
X48500Y112559D03*
X40940D03*
X40736Y127758D03*
Y130758D03*
X49236Y127758D03*
Y130758D03*
X39408Y195990D03*
X47948Y201000D03*
X39900Y211000D03*
X39493Y222932D03*
X41993D03*
X44149Y227332D03*
X39493Y220332D03*
X41993D03*
X44149Y224732D03*
X48059Y214825D03*
X48023Y217860D03*
X39800Y213800D03*
X35700Y218000D03*
X35600Y241200D03*
Y238200D03*
X51500Y258200D03*
X37485Y258807D03*
X41100Y248900D03*
X46220Y277170D03*
X47440Y304225D03*
X39039Y301299D03*
X47440Y301336D03*
X39039Y304278D03*
X50950Y318050D03*
X43500Y317100D03*
X48420Y321616D03*
X44200Y332000D03*
X44525Y324000D03*
X39100Y321600D03*
X44481Y328760D03*
X38560Y329739D03*
X35500Y340500D03*
Y335000D03*
X44220Y341008D03*
X44500Y344000D03*
X37400Y359900D03*
X44500Y348000D03*
X44525Y360000D03*
X35100Y352400D03*
X44500Y351600D03*
X35900Y363025D03*
X37800Y371225D03*
X44525Y364000D03*
Y368000D03*
X37300Y375000D03*
X44525Y376000D03*
X37875Y377925D03*
X44525Y387800D03*
X37735Y391200D03*
X44525Y391650D03*
X35101Y381610D03*
X44525Y384000D03*
X37020Y385600D03*
X47075Y391730D03*
X44500Y380000D03*
X44490Y397850D03*
X44525Y394150D03*
X36911Y394915D03*
X37067Y398337D03*
X44341Y406480D03*
X44330Y401450D03*
X39530Y409100D03*
X42900Y412900D03*
X46100Y412700D03*
X41200Y429100D03*
X43600Y422800D03*
X42200Y435900D03*
X38000Y428800D03*
X48050Y436350D03*
X45100Y435800D03*
X46100Y422800D03*
X54200Y25400D03*
X58976Y36402D03*
X53600Y44100D03*
X56348Y36210D03*
X50710Y54724D03*
X55000Y76000D03*
X63086Y65762D03*
X52120Y78373D03*
X59240Y67242D03*
X52502Y80978D03*
X53434Y106562D03*
X53400Y102788D03*
X59945Y117795D03*
Y120630D03*
X52237Y129522D03*
X60800Y137000D03*
X61123Y133070D03*
X52876Y195712D03*
X52410Y186900D03*
X59700Y196200D03*
X52410Y190190D03*
X52050Y208760D03*
X64050Y201010D03*
X52948Y200700D03*
X58000Y217700D03*
X58823Y213531D03*
X51600Y241200D03*
X59850Y235830D03*
X51010Y233570D03*
X49700Y242900D03*
X50567Y238630D03*
X50700Y250400D03*
X61200Y282600D03*
X58900Y288075D03*
X54660Y311660D03*
X60613Y312012D03*
X60600Y318000D03*
X64230Y303210D03*
X56600Y320500D03*
Y324300D03*
X52800Y322400D03*
X63000Y324100D03*
X56600Y318000D03*
X52820Y325200D03*
X60225Y336099D03*
X57400Y345400D03*
X52900Y360000D03*
X52600Y376600D03*
X58035Y370100D03*
X54400Y374700D03*
X55294Y369729D03*
X52475Y364000D03*
X52765Y390200D03*
X59500Y394000D03*
X58620Y408779D03*
X63200Y408600D03*
X52330Y413350D03*
X59511Y424477D03*
X60622Y431273D03*
X64122D03*
X56250Y424200D03*
X52750D03*
X54100Y448600D03*
X56500Y447600D03*
X56482Y456844D03*
Y453344D03*
X63569Y456844D03*
Y453344D03*
X68500Y66500D03*
X75280Y75704D03*
X72500Y66500D03*
X74757Y89745D03*
Y92745D03*
Y86745D03*
Y83745D03*
X66830Y122329D03*
X66900Y125300D03*
X66874Y130590D03*
X72300Y159400D03*
X68600Y159160D03*
X76442Y166907D03*
X73550Y166680D03*
X67330Y169267D03*
X68960Y173300D03*
X75284Y180800D03*
X71124Y178565D03*
X75300Y183875D03*
X71146Y186489D03*
X71370Y188993D03*
X67386Y191935D03*
X67486Y188977D03*
X74046Y186490D03*
X71600Y200900D03*
X72150Y204810D03*
X76670Y208772D03*
X75000Y214000D03*
X72500D03*
X70453Y222900D03*
X74583Y217314D03*
X70900Y241500D03*
X71100Y233575D03*
X67700Y229725D03*
X68990Y257000D03*
X77010Y256645D03*
X65755Y256045D03*
X76200Y247400D03*
X73011Y246365D03*
X77384Y253769D03*
X68800Y253300D03*
X68990Y260465D03*
X77437Y262760D03*
X77900Y274700D03*
X70000Y280000D03*
X78600Y283970D03*
X75960Y284049D03*
X65100Y282475D03*
X72700Y301200D03*
X75870Y290700D03*
X78770Y290708D03*
X73400Y313700D03*
X77500Y316100D03*
X68500Y325100D03*
X81000Y321900D03*
X76900Y323000D03*
X76500Y325500D03*
X78700Y340000D03*
X78900Y336600D03*
X71700Y340600D03*
X71000Y394400D03*
X67900Y400525D03*
X79000Y395500D03*
X73976Y408665D03*
X77860Y408678D03*
X77592Y413437D03*
X69139Y413452D03*
X66319Y413492D03*
X74782Y413800D03*
X67000Y408800D03*
X69700D03*
X69030Y422653D03*
X68100Y425400D03*
X71200Y431700D03*
X72150Y424199D03*
X75650D03*
X77600Y431400D03*
X79010Y445750D03*
X72800Y437900D03*
X88000Y66500D03*
X84500D03*
X90151Y68985D03*
X91358Y89745D03*
Y92745D03*
Y86745D03*
Y83745D03*
X86700Y119100D03*
X92500Y116200D03*
X89256Y135056D03*
X86100Y153340D03*
X89170Y141540D03*
X89200Y138800D03*
X86100Y155840D03*
X83410Y161020D03*
X86100Y158390D03*
X83520Y158520D03*
X81500Y176515D03*
X80788Y190812D03*
X82370Y197010D03*
X91300Y252900D03*
X80300Y243700D03*
X80270Y247830D03*
X90800Y258225D03*
X83500Y266900D03*
X84016Y258230D03*
X91500Y267000D03*
X92300Y282100D03*
X90923Y293520D03*
X85500Y326700D03*
X92698Y323224D03*
X93288Y330289D03*
X81900Y337100D03*
X81700Y342600D03*
X90500Y397600D03*
X82500D03*
X89487Y408435D03*
X87600Y414500D03*
X87800Y410300D03*
X84801Y409760D03*
X92500Y408630D03*
X86481Y407871D03*
X96030Y409400D03*
X81552Y409660D03*
X84320Y430510D03*
X93259Y424200D03*
X88565Y426535D03*
X79600Y426400D03*
X81990Y448085D03*
X85490D03*
X92870Y437831D03*
X89700Y437900D03*
X92801Y452793D03*
X107000Y44500D03*
X102190Y63225D03*
X104600Y50501D03*
X98500Y66500D03*
X102190Y66725D03*
X111000Y77000D03*
X104500Y73500D03*
X107124Y71004D03*
X108800Y91900D03*
X104425Y82500D03*
X110950Y82050D03*
X106000Y91900D03*
X111075Y104600D03*
X100360Y116500D03*
X102999Y131799D03*
X108270Y138630D03*
X95950Y152900D03*
X95944Y149687D03*
X98720Y236980D03*
X103580Y237400D03*
X106600Y253689D03*
X95300Y247100D03*
X97177Y263320D03*
X102600Y267000D03*
X107200Y265000D03*
X106800Y262076D03*
X106574Y280028D03*
X106100Y282900D03*
X100700Y293600D03*
X108551Y294241D03*
X99990Y311200D03*
Y307900D03*
X105100Y309300D03*
X94400Y311100D03*
Y307200D03*
X100500Y328547D03*
X105755Y327719D03*
X103000Y323800D03*
X95060Y327625D03*
X106852Y323292D03*
X97800Y325700D03*
X99026Y338368D03*
X103180Y336286D03*
X108108Y395100D03*
X98100Y412400D03*
X105500Y418200D03*
X100457Y409100D03*
X108701Y418300D03*
X98300Y407600D03*
X108336Y411547D03*
X108500Y408680D03*
X109048Y425853D03*
X104112Y422946D03*
X103461Y425875D03*
X95845Y424755D03*
X106700Y447730D03*
X95770Y437920D03*
X95870Y445483D03*
X99370D03*
X103900Y447640D03*
X96301Y452793D03*
X119000Y44600D03*
X115000Y44500D03*
X125800Y47330D03*
X112800Y60400D03*
X112600Y52800D03*
X118500Y75500D03*
X116500Y74000D03*
X109121Y69500D03*
X119700Y89200D03*
X123710Y82300D03*
X123740Y79791D03*
X115025Y104800D03*
X123325Y111000D03*
X120724Y108937D03*
X109350Y115501D03*
X109200Y118500D03*
X120500Y115525D03*
X109200Y128500D03*
X118990Y131580D03*
X109670Y136060D03*
X118692Y137304D03*
X120800Y147200D03*
X117800D03*
X113000Y160700D03*
X115400Y159500D03*
X113000Y158000D03*
X122156Y157844D03*
X122900Y170100D03*
X123120Y213088D03*
X123790Y227656D03*
X123690Y230156D03*
X122876Y242800D03*
X117840Y242200D03*
X121200Y234890D03*
X112200Y234520D03*
X116143Y230790D03*
X112900Y239200D03*
X111400Y254680D03*
X122876Y245300D03*
X120020Y254430D03*
X119105Y251511D03*
X117400Y266500D03*
X109800Y264928D03*
X111600Y262730D03*
X111100Y273700D03*
X111600Y284000D03*
X120070Y273700D03*
X115000D03*
X122957Y300991D03*
X123100Y295974D03*
X120600Y293471D03*
X110565Y296331D03*
X124935Y324900D03*
X115535Y335235D03*
X124300Y348800D03*
X115600Y337900D03*
X114700Y351200D03*
X121200Y359200D03*
X111330Y357800D03*
X120200Y361600D03*
X114700Y348500D03*
X111460Y361770D03*
X111950Y371200D03*
X122047Y372260D03*
X125650Y368650D03*
X122330Y364670D03*
X111869Y365454D03*
X121175Y385125D03*
X119200Y389700D03*
X117410Y381350D03*
X110900Y378500D03*
X123100Y390600D03*
X119200Y406175D03*
X122600Y394600D03*
X119026Y393332D03*
X119791Y412301D03*
X112800Y421600D03*
X113000Y416200D03*
X116632Y411500D03*
X122498Y419675D03*
X112796Y412490D03*
X119500Y433600D03*
X111510Y434710D03*
X121700Y424005D03*
X123170Y433200D03*
X126425Y57000D03*
X133000Y59900D03*
X140730Y72600D03*
X130500Y74700D03*
X129300Y82650D03*
X131470Y81260D03*
X129500Y91475D03*
X131528Y114271D03*
X135500Y138000D03*
Y135000D03*
X134400Y127652D03*
X132828Y138400D03*
X133500Y146800D03*
X138458Y146458D03*
X132500Y167300D03*
X126500Y158000D03*
X133690Y158100D03*
X136190D03*
X126500Y174000D03*
X137900Y179160D03*
X135300Y175100D03*
X125700Y183700D03*
X129810Y191310D03*
X124338Y204742D03*
X124779Y201633D03*
X126153Y199079D03*
X135000Y221200D03*
X132500Y221900D03*
X138100Y213600D03*
X134891Y225171D03*
X124226Y225194D03*
X134358Y230069D03*
X130167Y234733D03*
X138000Y244600D03*
X133000Y256100D03*
X128760Y265726D03*
X127600Y259700D03*
X135315Y279813D03*
X125100Y273720D03*
X128760Y273701D03*
X137083Y278045D03*
X137196Y274491D03*
X132420Y273811D03*
X138600Y295900D03*
X124100Y311100D03*
X136100Y334000D03*
X129800Y325800D03*
X138590Y345710D03*
X124400Y345300D03*
X125910Y335006D03*
X125900Y337600D03*
X133300Y334100D03*
X136000Y341000D03*
X133000Y361500D03*
X132600Y350090D03*
X124350Y352450D03*
X129776Y374500D03*
X138700Y376600D03*
X126340Y382700D03*
X125174Y393916D03*
X135300Y399900D03*
X137900Y399500D03*
X131540Y394690D03*
X132700Y402700D03*
X133500Y409110D03*
X129135Y410250D03*
X133070Y420874D03*
X134300Y416414D03*
X136230Y423935D03*
X128866Y433066D03*
X135350Y433016D03*
X124500Y424005D03*
X132070Y433110D03*
X133572Y423935D03*
X125930Y433110D03*
X138750Y451500D03*
Y454500D03*
X152800Y75600D03*
X145000Y90700D03*
X145100Y87400D03*
X142400Y91300D03*
X141100Y86500D03*
X148819Y123197D03*
X143400Y121700D03*
X141220Y123070D03*
X147600Y117000D03*
X151800Y116500D03*
X152800Y111600D03*
X148819Y125697D03*
X149800Y138100D03*
Y135100D03*
X145185Y134214D03*
X142892Y136645D03*
X143269Y150456D03*
X150155Y145086D03*
X152556Y147683D03*
X148429Y147682D03*
X144500Y169570D03*
X146300Y161010D03*
X140554Y168887D03*
X153200Y170990D03*
X140554Y171688D03*
X146882Y177501D03*
X150619Y178646D03*
X145296Y188835D03*
X140830Y192530D03*
X153051Y187354D03*
X150005Y184973D03*
X149100Y189963D03*
X144280Y195130D03*
X151940Y203710D03*
X151900Y213200D03*
X143980Y199674D03*
X147800Y200789D03*
X140903Y199421D03*
X143742Y203395D03*
X152500Y199500D03*
X145500Y227700D03*
X142702Y227817D03*
X153100Y234800D03*
X149862Y243788D03*
X142085Y230549D03*
X151040Y237870D03*
X145250Y256890D03*
X145580Y248082D03*
X141280Y256310D03*
X149215Y267745D03*
X152400Y284400D03*
X150240Y277940D03*
X152500Y289425D03*
X150293Y302117D03*
X147500Y289405D03*
X141890Y310570D03*
X151320Y322700D03*
X148600Y336300D03*
X142202Y334000D03*
X142300Y336700D03*
X144800D03*
X144700Y334100D03*
X153419Y341978D03*
X143945Y354146D03*
X148316Y359086D03*
X141045Y355309D03*
X150900Y360325D03*
X151695Y357900D03*
X149500Y356700D03*
X141000Y358500D03*
X145703Y370700D03*
X139200Y372510D03*
X149000Y383070D03*
X152100Y378400D03*
X152500Y382600D03*
X150820Y387325D03*
X141520Y399700D03*
X139400Y392460D03*
X151265Y399500D03*
X142511Y393690D03*
X153079Y412000D03*
X149600Y410500D03*
X139700Y415100D03*
X150000Y414750D03*
X143000Y414600D03*
X140600Y412300D03*
X148060Y423500D03*
X148100Y433400D03*
X152200Y423100D03*
X148041Y426700D03*
X138987Y423935D03*
X151398Y449930D03*
X158246Y78872D03*
X156710Y73420D03*
X163423Y96281D03*
X159923D03*
X166200Y105500D03*
X155530Y116640D03*
X156286Y124903D03*
X156200Y111600D03*
X162657Y117297D03*
X154050Y137100D03*
X159000Y135000D03*
X166700Y132360D03*
X156406Y129203D03*
X162419Y131032D03*
X166733Y128700D03*
X155325Y139440D03*
X153954Y145086D03*
X161900Y150500D03*
X165690Y149622D03*
X159328Y160847D03*
X156481Y155933D03*
X162200Y158200D03*
X159900Y155600D03*
X161240Y177820D03*
X161237Y181735D03*
X156467Y203500D03*
X162594Y212585D03*
Y210085D03*
X166140Y205955D03*
X165381Y201274D03*
X153744Y217435D03*
X153800Y214900D03*
X162653Y218843D03*
X159643Y226484D03*
X162200Y221376D03*
X163500Y229184D03*
X167200Y222600D03*
X161200Y233600D03*
X165500Y236100D03*
X157200Y240000D03*
X156970Y255000D03*
X165013Y254986D03*
X160973D03*
X164500Y266000D03*
X160590Y263300D03*
X156970Y263250D03*
X164800Y263300D03*
X158750Y284949D03*
X168392Y298493D03*
X160850Y301344D03*
X168300Y301100D03*
X162100Y291600D03*
X161400Y307600D03*
X162160Y313560D03*
X170800Y317600D03*
X164500Y314800D03*
X155000Y321100D03*
X168557Y341221D03*
X158459Y340898D03*
X158467Y344067D03*
X161300Y354600D03*
X161154Y376704D03*
X156300Y376300D03*
X154500Y387350D03*
X159050Y387334D03*
X162550D03*
X165500Y386000D03*
X165501Y382800D03*
X158200Y381400D03*
X155452Y401000D03*
X160540Y416912D03*
X162100Y414000D03*
X157294Y435623D03*
X156101Y425100D03*
X167008Y430718D03*
X165500Y433100D03*
X167865Y427771D03*
X163700Y422119D03*
X159396Y449408D03*
X160700Y445550D03*
X158100Y442700D03*
X168029Y456660D03*
X157500Y453390D03*
X176900Y14625D03*
X178200Y76145D03*
X175700Y76245D03*
X179900Y91300D03*
X181960Y99260D03*
X169700Y102250D03*
X176300Y98700D03*
X172847Y96281D03*
X169347D03*
X179500Y116800D03*
X182000Y117200D03*
X171600Y114000D03*
X182865Y113706D03*
X174600Y114000D03*
X169100Y113900D03*
X182103Y132294D03*
X182108Y129094D03*
X170867Y128211D03*
X178290Y128824D03*
X174553Y128728D03*
X176550Y125210D03*
X178284Y132394D03*
X170610Y131900D03*
X174436Y132394D03*
X168800Y126800D03*
X172100Y146300D03*
X176000Y140500D03*
X172890Y153260D03*
X171700Y156900D03*
X169500Y180200D03*
X170800Y193100D03*
X172621Y208300D03*
X173800Y225400D03*
X170400Y214700D03*
X172400Y220700D03*
X175300Y240000D03*
X174400Y254736D03*
X179846Y255150D03*
X180458Y258825D03*
X174400Y251936D03*
X176900Y270100D03*
X174292Y263300D03*
X171592Y263312D03*
X168710Y272256D03*
X172977Y277000D03*
X182435Y281797D03*
X179217Y278528D03*
X168656Y275156D03*
X182232Y296424D03*
X174232Y304333D03*
X176563Y310917D03*
X176533Y314049D03*
X170550Y304050D03*
X169077Y308677D03*
X170561Y306631D03*
X181050Y332250D03*
X171098Y341224D03*
X182700Y342216D03*
X180600Y360200D03*
X177500Y369100D03*
X178850Y385634D03*
X182350D03*
X172530Y420950D03*
Y429470D03*
X184480Y429370D03*
X171400Y450600D03*
X193100Y69100D03*
X189400Y69600D03*
X184800Y100300D03*
X187700Y99000D03*
X187400Y101500D03*
X190800Y117200D03*
X193096Y115600D03*
X186891Y113991D03*
X190744Y114456D03*
X187069Y116800D03*
X184729Y115820D03*
X187435Y129623D03*
X195983Y132294D03*
X191482Y129294D03*
X195983D03*
X186200Y125600D03*
X184000Y140500D03*
X196577Y141185D03*
X189700Y140400D03*
X191693Y236370D03*
X196240Y253430D03*
X193084Y257400D03*
X194567Y255288D03*
X187400Y255700D03*
X190900Y271700D03*
X193386Y269142D03*
X184200Y264900D03*
X185000Y270700D03*
X195370Y273297D03*
X183625Y273500D03*
X196200Y278200D03*
X196100Y281820D03*
X187623Y297475D03*
X192380Y291900D03*
X196443Y294065D03*
X191199Y300200D03*
X192448Y308314D03*
X195031Y307182D03*
X194600Y313300D03*
X197853Y307200D03*
X197155Y314223D03*
X188546Y326356D03*
X190465Y344426D03*
X190600Y337900D03*
X183800Y345400D03*
X197775Y346617D03*
X194800Y341700D03*
X191408Y357451D03*
X197450Y356560D03*
X196050Y358770D03*
X191420Y354710D03*
X190965Y348090D03*
X197711Y349250D03*
X195000Y373900D03*
X187400Y379400D03*
X197400Y367600D03*
Y370250D03*
X197620Y385425D03*
X187300Y384300D03*
X197660Y390870D03*
X190050Y389140D03*
X190100Y392270D03*
X191843Y403995D03*
X189054Y397500D03*
X194500Y402600D03*
X195800Y396780D03*
X185245Y417500D03*
X190370Y422490D03*
X195000Y422540D03*
X199940Y423700D03*
X197600Y415400D03*
X190270Y409962D03*
X189762Y429177D03*
X195300Y432327D03*
X189766Y432050D03*
X189838Y434910D03*
X186720Y432490D03*
X186300Y448700D03*
X185000Y451500D03*
Y454000D03*
Y456500D03*
X191780Y453300D03*
Y456700D03*
X211400Y59238D03*
X204300Y60600D03*
X201500Y61000D03*
X209142Y53664D03*
X204100Y67400D03*
X201900Y83300D03*
X199940Y117500D03*
X211370Y117000D03*
X208200Y111760D03*
X199985Y132294D03*
X212757Y127064D03*
X212727Y129654D03*
X208627Y132394D03*
X208576Y128957D03*
X204120Y132294D03*
X200000Y128764D03*
X208500Y126057D03*
X212727Y132154D03*
X211490Y143700D03*
X205598Y140480D03*
X203542Y213254D03*
X206200Y255385D03*
X200680Y257540D03*
X206051Y247911D03*
X205500Y258300D03*
X201100Y265120D03*
X214034Y261482D03*
X201000Y262500D03*
X203090Y269229D03*
X205590Y269129D03*
X205900Y266130D03*
X204258Y286691D03*
X213258Y273265D03*
X204560Y301130D03*
X212911Y293869D03*
X206430Y298780D03*
X199729Y314565D03*
X198672Y318175D03*
X208628Y324665D03*
X200300Y328800D03*
X208000Y373240D03*
X208565Y404501D03*
X200222Y398150D03*
X213200Y399166D03*
X199880Y402846D03*
X207539Y408686D03*
X200000Y407040D03*
X205223Y422665D03*
X207278Y416022D03*
X206150Y412821D03*
X198600Y426600D03*
X202513Y434800D03*
X198405D03*
X199000Y444500D03*
X205200Y445400D03*
X213225Y442220D03*
X214306Y62233D03*
X229900Y61000D03*
X224000Y74275D03*
X218600Y92100D03*
X221300D03*
X224330Y83210D03*
X227760Y82524D03*
X219900Y101300D03*
X216400Y106400D03*
X226040Y101220D03*
X222890Y101240D03*
X215294Y117094D03*
X226887Y117297D03*
X223300Y117400D03*
X217262Y129294D03*
X225284Y132294D03*
X229342Y129240D03*
X221278Y129294D03*
X225284D03*
X217262Y132294D03*
X221278D03*
X225300Y125200D03*
X227700Y151900D03*
X221000Y243000D03*
X220100Y237200D03*
X223800Y254800D03*
X227316Y256700D03*
X215100Y244100D03*
X215500Y247111D03*
X216800Y255550D03*
X215510Y253310D03*
X225275Y246000D03*
X217500Y264000D03*
X230196Y267477D03*
X219900Y267100D03*
X220866Y272160D03*
X227232Y270539D03*
X226405Y266335D03*
X222833Y261668D03*
X219722Y286728D03*
X227841Y275773D03*
X219339Y284138D03*
X219359Y281580D03*
X226500Y273000D03*
X229220Y283250D03*
X223646Y293960D03*
X214400Y303997D03*
X216384Y312216D03*
X228800Y312100D03*
X226100Y325065D03*
X217300Y322800D03*
X225867Y345033D03*
X225650Y337520D03*
X221000Y343800D03*
X216405Y335970D03*
X214175Y333740D03*
X228230Y340040D03*
X221000Y352000D03*
X224632Y369825D03*
X225700Y362500D03*
X213490Y373690D03*
X226710Y364815D03*
X223420Y367080D03*
X220515Y384900D03*
X222575Y387625D03*
X227206Y400100D03*
X217390Y401340D03*
X222986Y400323D03*
X220134Y400780D03*
X219050Y418850D03*
X217725Y410150D03*
X221225D03*
X226830Y435170D03*
X225000Y433100D03*
X219250Y422150D03*
X213900Y436000D03*
X217100Y436100D03*
X224000Y449100D03*
X216725Y442220D03*
X237000Y47200D03*
X234537Y74638D03*
X240000Y67400D03*
X230600Y91700D03*
X239660Y91920D03*
X232150Y82480D03*
X235630Y104990D03*
X231592Y110500D03*
X240160Y107000D03*
X240710Y99570D03*
X232325Y101230D03*
X236648Y100739D03*
X238900Y114800D03*
X234500Y117500D03*
X230293Y117417D03*
X239900Y117550D03*
X239206Y112300D03*
X233511Y132594D03*
X234900Y126100D03*
X229396Y132294D03*
X233511Y129594D03*
X242500Y129000D03*
X242195Y141003D03*
X232384Y148884D03*
X230535Y244564D03*
X237700Y257387D03*
X237730Y248085D03*
X242690Y255300D03*
X230000Y255700D03*
X232300Y261200D03*
X239298Y268800D03*
X242940Y268500D03*
X233033Y266483D03*
X229630Y264404D03*
X242087Y271427D03*
X238531Y263081D03*
X231900Y272700D03*
X241188Y279347D03*
X241263Y282654D03*
X234500Y293500D03*
X242700Y306800D03*
X240500Y316575D03*
X236688Y311217D03*
X238400Y304200D03*
X228800Y305500D03*
X235400Y303800D03*
X242592Y330683D03*
X243010Y323400D03*
X230445Y325945D03*
X235000Y335300D03*
X231689Y334896D03*
X233500Y346911D03*
Y343911D03*
X231500Y352500D03*
X233650Y359628D03*
X233800Y354300D03*
X230287Y373100D03*
X232470Y382280D03*
X233600Y377300D03*
X233790Y384490D03*
X239750Y394970D03*
X236670Y394550D03*
X241231Y407285D03*
X236860Y407300D03*
X229900Y436600D03*
X236900Y440565D03*
X239500Y447750D03*
X235400Y451600D03*
X231250Y447000D03*
X235200Y449100D03*
X231400Y449500D03*
X241436Y445784D03*
X240200Y450650D03*
X236221Y454400D03*
X240010Y456000D03*
X240210Y453400D03*
X231400Y452000D03*
X252925Y54000D03*
X249475Y55812D03*
X256000Y56000D03*
X246200Y74600D03*
X253000Y77500D03*
X250000Y73000D03*
X255000Y82700D03*
X257800Y82800D03*
X256900Y87300D03*
X251200Y93800D03*
X251900Y100100D03*
X255213Y106099D03*
X249988Y105792D03*
X246488D03*
X244208Y97302D03*
X247200Y117400D03*
X253100Y119900D03*
X245310Y113910D03*
X245500Y127800D03*
X245520Y130600D03*
X258500Y146400D03*
X251354Y152877D03*
X249300Y237600D03*
X247689Y247929D03*
X253110Y254909D03*
X253100Y257800D03*
X252639Y247885D03*
X256700Y263800D03*
X255700Y260000D03*
X247470Y269990D03*
X250288Y273581D03*
X251459Y286542D03*
Y283542D03*
X257145Y279700D03*
X246514Y294325D03*
Y296825D03*
X258100Y295080D03*
X254355Y300577D03*
X247923Y316400D03*
X245900Y305000D03*
X257900Y312100D03*
X248900Y304900D03*
X247923Y319000D03*
X253320Y323327D03*
X256124Y336355D03*
X243750Y369730D03*
X243700Y372730D03*
X244790Y375910D03*
X248800Y385700D03*
X249400Y410300D03*
X252350Y412850D03*
X257810Y435100D03*
X246700Y451500D03*
X246500Y448500D03*
X243375Y448375D03*
X246700Y454100D03*
X259000Y47500D03*
X267939Y41122D03*
X268500Y45500D03*
X259894Y90072D03*
X263102Y91725D03*
X272505Y83545D03*
X260050Y87026D03*
X265801Y106040D03*
X260970Y98600D03*
X258713Y106099D03*
X264989Y101732D03*
X271602Y121400D03*
X269561Y130987D03*
X271300Y132900D03*
X269493Y138604D03*
X260200Y132395D03*
X260388Y125001D03*
X268442Y153299D03*
X265942D03*
Y150799D03*
X268442D03*
X269004Y144450D03*
Y141950D03*
X269133Y164982D03*
X265226D03*
X268339Y222126D03*
X272300Y251000D03*
X258628Y247600D03*
X258475Y254872D03*
X267100Y265000D03*
X269016Y266991D03*
X259500Y263700D03*
X262730Y267600D03*
X258000Y266300D03*
X266600Y268700D03*
X262700Y265100D03*
X258000Y284900D03*
X262100Y280700D03*
X266250Y297900D03*
X266200Y294800D03*
X261500Y290440D03*
X266300Y307500D03*
X262310Y311225D03*
X264265Y315817D03*
X261300Y334100D03*
X271100Y346575D03*
X259420Y343230D03*
Y340630D03*
X273580Y354250D03*
X271990Y362360D03*
X265320Y392290D03*
X274190Y408900D03*
X265100Y395100D03*
X272400Y392400D03*
X269700Y411379D03*
X271500Y418300D03*
X267100Y432900D03*
X263800Y430300D03*
X272999Y430500D03*
X271710Y449840D03*
X266727Y443185D03*
X261700Y439700D03*
X265130Y440070D03*
X261100Y443500D03*
X269561Y456044D03*
X286000Y47000D03*
X277000Y51665D03*
X274500Y58000D03*
X279934Y51688D03*
X279800Y72700D03*
X290000Y82000D03*
X273400Y92800D03*
X276400Y92300D03*
X287578Y84092D03*
X283500Y89500D03*
X277505Y83545D03*
X282505D03*
X278300Y95019D03*
X274760Y105140D03*
X275386Y102710D03*
X280910Y102880D03*
X288116Y120306D03*
X285250Y117250D03*
X274200Y109500D03*
X280400Y126000D03*
X283500D03*
X275960Y126010D03*
X273450Y125050D03*
X287796Y131542D03*
X288280Y126212D03*
X280616Y150971D03*
X283616D03*
X287555Y142419D03*
X285899Y153542D03*
X283399D03*
X279457Y171318D03*
X279983Y235254D03*
X282483D03*
X283974Y251372D03*
X286800Y251400D03*
X276200Y251500D03*
X280082Y251328D03*
X280030Y267098D03*
Y264098D03*
X284357Y267027D03*
Y264027D03*
X285911Y269899D03*
X281889D03*
X287755Y287538D03*
X282911Y279569D03*
X285911D03*
X287507Y301596D03*
X281300Y308800D03*
X287050Y305850D03*
X289939Y309060D03*
X276660Y316900D03*
X273355Y330001D03*
X286372Y320700D03*
X289600Y322253D03*
X286372Y326768D03*
X285860Y336131D03*
X277500Y348469D03*
X275520Y357910D03*
X277290Y355820D03*
X277572Y351198D03*
X287761Y366200D03*
X287500Y376900D03*
X276145Y366455D03*
X276400Y370400D03*
X283664Y379236D03*
X273100Y381500D03*
X283973Y382553D03*
X285191Y390840D03*
X287630Y389378D03*
X275700Y403500D03*
X277700Y406100D03*
X287476Y396680D03*
X278900Y421400D03*
X281300Y416200D03*
X277700Y412580D03*
X287500Y416100D03*
X278409Y433722D03*
X276400Y431810D03*
X275100Y427682D03*
X274619Y424725D03*
X283622Y447155D03*
X275138Y451215D03*
X276632Y439502D03*
X283674Y449975D03*
X283715Y452769D03*
X297466Y51521D03*
X300425Y54516D03*
X290000Y67975D03*
X297575Y73738D03*
X293773Y73530D03*
X300070Y84000D03*
X294600Y106900D03*
X298575Y101900D03*
X304000Y116500D03*
X294800Y111800D03*
X298975Y118900D03*
X301000Y121016D03*
X300500Y125000D03*
X295075Y119100D03*
X301000Y129900D03*
X290200Y129500D03*
X298005Y151118D03*
Y148618D03*
Y146118D03*
X292204Y142610D03*
X301936Y143897D03*
X296734Y216079D03*
X290586Y234844D03*
X288086D03*
X301120Y235626D03*
Y238765D03*
X299138Y244513D03*
X291500Y287670D03*
Y285170D03*
X298840Y279640D03*
X291000Y297700D03*
X291300Y315900D03*
X290120Y339370D03*
X290000Y335600D03*
X300700Y341300D03*
X295500Y354920D03*
X296780Y371500D03*
X298152Y393332D03*
X292700Y403700D03*
X291623Y447747D03*
X291703Y450819D03*
X295729Y453912D03*
Y456912D03*
Y459912D03*
X297738Y452418D03*
Y458418D03*
Y455418D03*
X316025Y60200D03*
X309570Y84000D03*
X316066Y108407D03*
X315100Y116400D03*
X307400Y122300D03*
X315900Y125900D03*
X313800Y124300D03*
X307560Y128500D03*
X305936Y143897D03*
X309936D03*
X313936D03*
X307487Y219503D03*
X304987D03*
X310449Y218617D03*
X317110Y219140D03*
X309521Y235352D03*
Y238741D03*
X305000Y252400D03*
X307600Y252300D03*
X307800Y259200D03*
X312272Y282107D03*
X302800Y286200D03*
X311670Y285160D03*
X302879Y282487D03*
Y279686D03*
X309700Y294789D03*
X306500Y301500D03*
X303000Y309200D03*
X306200Y308800D03*
X312300Y340700D03*
X308906Y362637D03*
X314340Y373296D03*
X311925Y366475D03*
X308926Y401900D03*
X321800Y60055D03*
X322500Y102900D03*
X320500Y100400D03*
X324011Y118843D03*
X324023Y121943D03*
Y115643D03*
X320765Y114582D03*
X320938Y122677D03*
X318000Y117200D03*
X331741Y138243D03*
Y125796D03*
X317936Y143897D03*
X323509Y153377D03*
X329005Y152657D03*
X328087Y141608D03*
X331641Y141743D03*
X321600Y142100D03*
X331405Y164911D03*
Y159911D03*
Y154911D03*
Y167411D03*
Y179911D03*
Y174911D03*
Y169911D03*
Y182926D03*
Y172411D03*
Y189911D03*
X320054Y195163D03*
X326932Y205685D03*
X326733Y209885D03*
X321045Y210257D03*
X320937Y212839D03*
X326733Y201485D03*
X320054Y198663D03*
X326731Y213648D03*
X320931Y215387D03*
X317922Y238717D03*
Y235328D03*
X326323Y235304D03*
Y238693D03*
X327162Y278972D03*
X325007Y328608D03*
Y326008D03*
X327704Y328635D03*
Y326035D03*
X325007Y323508D03*
X327704Y323535D03*
X329925Y356016D03*
X325900Y365643D03*
X326100Y375717D03*
X326200Y370681D03*
X331500Y383300D03*
X326375Y380724D03*
X325593Y406500D03*
X329093D03*
X318593D03*
X322093D03*
X339900Y69100D03*
Y66000D03*
X339908Y104577D03*
Y108593D03*
X342200Y100500D03*
X342180Y106900D03*
X339908Y112609D03*
X339369Y151952D03*
X339939Y162911D03*
X339812Y173380D03*
X339800Y182926D03*
X337400Y193449D03*
X334724Y238669D03*
Y235280D03*
X337467Y236984D03*
X336461Y283202D03*
X340612Y278972D03*
X339700Y293000D03*
X347100Y313700D03*
X345500Y342690D03*
X335475Y358500D03*
Y367500D03*
X335708Y372008D03*
X335500Y380000D03*
X375904Y-438145D03*
X375964Y-215959D03*
X375876Y-159873D03*
X375964Y12313D03*
X375904Y68399D03*
X375964Y381585D03*
X379304Y-438145D03*
X379364Y-215959D03*
X379276Y-159873D03*
X379364Y12313D03*
X379304Y68399D03*
X379364Y381585D03*
X396992Y-464207D03*
X400392D03*
X397080Y-121021D03*
X400480D03*
G54D23*
X23819Y339154D03*
Y359154D03*
Y369154D03*
Y379154D03*
Y389154D03*
Y399154D03*
Y409154D03*
X65709Y42244D03*
Y52244D03*
X75709Y42244D03*
Y52244D03*
X95709Y42244D03*
X85709D03*
Y52244D03*
G54D25*
X63898Y24764D03*
X73898D03*
X90472D03*
X100472D03*
X117047D03*
X127047D03*
X211142D03*
X237717D03*
X247717D03*
G54D28*
X62458Y346425D03*
Y343275D03*
Y355873D03*
X58564Y354280D03*
X65607Y352724D03*
Y359023D03*
Y371584D03*
X75056Y346425D03*
X68757D03*
X81355D03*
X78206Y349574D03*
X71906D03*
X68757D03*
X78206Y359023D03*
X75056Y352724D03*
Y349574D03*
X78206Y355873D03*
X65607D03*
X68757Y362173D03*
Y359023D03*
X71906D03*
X75056Y355873D03*
X71906Y352724D03*
X68757Y355873D03*
X78206Y374733D03*
Y362173D03*
X75056D03*
X71906Y371584D03*
X75056Y365322D03*
X71906D03*
X68757D03*
Y371584D03*
X75056Y374733D03*
X71906D03*
X68757D03*
X65607D03*
X71906Y362173D03*
X78206Y365322D03*
Y371584D03*
X68757Y377883D03*
X78206Y381033D03*
X65607D03*
X71906Y377883D03*
X65607Y384182D03*
X68719Y381033D03*
X78206Y377883D03*
X71906Y387332D03*
X71869Y381033D03*
X71906Y384182D03*
X87617Y352724D03*
X90766Y349574D03*
X93916Y352724D03*
X81355Y355873D03*
X90766Y352724D03*
X87617Y349574D03*
X90766Y355873D03*
X87617D03*
X90766Y359023D03*
X81355Y349574D03*
X87617Y359023D03*
X90766Y374733D03*
Y362173D03*
X81355D03*
X87617D03*
X81355Y374733D03*
X87617D03*
X90766Y371584D03*
Y365322D03*
X81355Y377883D03*
Y387332D03*
Y384182D03*
X87617D03*
X90766Y377883D03*
X87617Y390481D03*
X81355Y381033D03*
X87617Y387332D03*
X90766Y381033D03*
X87617Y377883D03*
X90766Y390481D03*
Y387332D03*
Y384182D03*
X92360Y394175D03*
X89210D03*
X103365Y346425D03*
X106564Y346400D03*
X100253Y346387D03*
X93916Y349574D03*
X97066D03*
X106515Y352724D03*
X106514Y349574D03*
X97066Y352724D03*
X100215Y355873D03*
X93916D03*
X100215Y349574D03*
Y387332D03*
X97066D03*
X93916Y384182D03*
X97066D03*
X100215Y381033D03*
X93916D03*
Y387332D03*
X166300Y212300D03*
X181495Y153449D03*
X175196Y159748D03*
X178346Y156599D03*
X181495Y159748D03*
X175196Y156599D03*
X181495D03*
Y166047D03*
X184645D03*
X181495Y162898D03*
X178346Y159748D03*
X181495Y178646D03*
Y175496D03*
X184645Y181795D03*
X181495D03*
Y172347D03*
X184645Y175496D03*
X174569Y180202D03*
X178346Y175496D03*
X175196Y172347D03*
X173000Y170200D03*
X181495Y169197D03*
Y184945D03*
Y197506D03*
X178346D03*
Y191244D03*
X181495D03*
X175196Y197506D03*
X174336Y192800D03*
X181495Y188095D03*
X178346D03*
X175196Y200655D03*
X178346Y210104D03*
X181495Y203805D03*
Y206955D03*
X175196Y210104D03*
X178346Y206955D03*
X175196D03*
Y203805D03*
X178346D03*
X171836Y200655D03*
Y198300D03*
X181495Y200655D03*
Y219553D03*
X175196Y213254D03*
X184645Y219553D03*
X178346Y229002D03*
X181495Y225852D03*
Y222703D03*
X184645Y229002D03*
X174600Y217800D03*
X181495Y216403D03*
X175196Y229002D03*
X181495D03*
X187794Y153449D03*
X192400Y152804D03*
X184645Y153449D03*
X197243Y166047D03*
X194094Y162898D03*
X197243Y159748D03*
X194094D03*
X197243Y162898D03*
X184645Y156599D03*
X187794Y162898D03*
Y166047D03*
X184645Y162898D03*
Y159748D03*
X190944Y162898D03*
Y159748D03*
X194094Y166047D03*
X190944D03*
X200393Y162898D03*
X187794Y156599D03*
Y178646D03*
X194094Y169197D03*
X190944Y172347D03*
Y175496D03*
X197243D03*
X190944Y178646D03*
Y181795D03*
X187794Y175496D03*
X184645Y178646D03*
X190944Y169197D03*
X187794Y172347D03*
X184645Y169197D03*
Y172347D03*
X187794Y169197D03*
X197243Y184945D03*
X190944Y197506D03*
Y184945D03*
Y188095D03*
Y191244D03*
X187794Y197506D03*
Y184945D03*
X184645Y197506D03*
Y184945D03*
Y191244D03*
Y188095D03*
X190944Y200655D03*
Y210104D03*
Y203805D03*
X187794Y200655D03*
X184645Y210104D03*
Y200655D03*
Y203805D03*
X187794Y210104D03*
X190944Y219553D03*
X194094Y222703D03*
X200393Y229002D03*
X194094Y225852D03*
X187794D03*
Y219553D03*
X190944Y213254D03*
Y222702D03*
X200393Y222703D03*
X197243Y225852D03*
Y222703D03*
X184645Y225852D03*
X187794Y222703D03*
X184645D03*
Y213254D03*
X194094Y219553D03*
X187794Y229002D03*
X197243Y235301D03*
X194094Y229002D03*
X197243D03*
Y232151D03*
X209842Y153449D03*
Y159748D03*
X206692Y156599D03*
X203542Y166047D03*
X206692Y162898D03*
X203542D03*
X200393Y159748D03*
X209842Y166047D03*
Y162898D03*
X212991D03*
X203542Y159748D03*
X200393Y166047D03*
X206692D03*
X212991D03*
X206692Y159748D03*
X209842Y169197D03*
X206692Y181795D03*
X203542Y175496D03*
X206692D03*
X209842D03*
X200393D03*
X212991Y184945D03*
Y197506D03*
X203542Y206955D03*
X212991Y203805D03*
X206692Y206955D03*
X209842D03*
X200393D03*
X212991Y200655D03*
Y213254D03*
X200393D03*
Y219553D03*
X212991Y222740D03*
X209842Y213254D03*
Y225852D03*
X203542Y222703D03*
X200393Y225852D03*
X206692Y219553D03*
X203542Y225852D03*
X206692Y229002D03*
X212991D03*
X203542Y219553D03*
X206692Y222703D03*
X209842D03*
X212991Y225890D03*
X206692Y225852D03*
X203542Y229002D03*
X209746Y235397D03*
X203542Y235301D03*
X209842Y232151D03*
X200393D03*
X206692D03*
X212991D03*
X209842Y229002D03*
X225658Y153369D03*
X225552Y159748D03*
X222402Y162898D03*
X219253Y166047D03*
X225552Y162898D03*
Y166047D03*
X222402D03*
X219253Y159748D03*
X222402D03*
X219253Y162898D03*
Y156599D03*
X222402D03*
Y178646D03*
X225552Y181795D03*
X214547Y174852D03*
X225552Y169197D03*
X219253D03*
X225552Y191244D03*
Y188095D03*
X222402Y191244D03*
X219253Y197506D03*
X222402D03*
X219253Y188095D03*
Y200655D03*
Y206955D03*
Y210104D03*
Y203805D03*
Y213254D03*
X228739Y222703D03*
X216141D03*
X228702Y229002D03*
X225590Y222720D03*
X216103Y219591D03*
X219253Y219553D03*
X225590Y225852D03*
X222440Y222703D03*
X225552Y219553D03*
X222402D03*
Y229002D03*
X222440Y225852D03*
X219290D03*
Y222703D03*
X225552Y229002D03*
X219253D03*
X235001Y153449D03*
X228702Y162898D03*
X238150D03*
X231851Y166047D03*
X238150D03*
X228702Y159748D03*
Y166047D03*
X238150Y156599D03*
X235001D03*
X231851D03*
Y162898D03*
Y159748D03*
X235001Y162898D03*
Y159748D03*
X238150D03*
X241300D03*
X231851Y169197D03*
Y178646D03*
X235001Y169197D03*
X241300Y175496D03*
Y178646D03*
Y172347D03*
X235001Y178646D03*
Y175496D03*
X228702Y181795D03*
Y178646D03*
X235001Y188095D03*
Y191244D03*
Y197506D03*
X241300Y184945D03*
Y197506D03*
Y188095D03*
X244450Y200655D03*
X228702D03*
X235001Y203805D03*
X231851D03*
X228702D03*
X241300Y200655D03*
Y210104D03*
X235001D03*
X231851D03*
X228702D03*
X235038Y225890D03*
X228739Y225852D03*
X238150Y222703D03*
X231889Y219591D03*
Y222740D03*
X235038D03*
X231889Y225890D03*
X228739Y216441D03*
X241338Y225890D03*
X231851Y229002D03*
X241300D03*
X239870Y237596D03*
X242870D03*
X235038Y229039D03*
X250749Y169197D03*
X247637Y162898D03*
X247599Y166047D03*
X253898Y169197D03*
X257048Y172347D03*
X250749Y181795D03*
X244450D03*
X250749Y175496D03*
Y178646D03*
X247599Y172347D03*
X244450Y175496D03*
X250749Y172347D03*
X247599Y178646D03*
X253898Y175496D03*
X244450Y178646D03*
Y172347D03*
X250749Y184945D03*
X244450Y169197D03*
Y197506D03*
X247599Y191244D03*
X257048Y197506D03*
X253898D03*
X250749D03*
X247599Y184945D03*
X244450Y188095D03*
X257048Y191244D03*
X250749Y188095D03*
X244450Y184945D03*
X250749Y191244D03*
X244450D03*
X250749Y203805D03*
X247599Y206955D03*
Y210104D03*
X250749Y206955D03*
X247599Y200655D03*
X257048Y206955D03*
X250749Y200655D03*
X257048D03*
X250749Y210104D03*
X244450Y203805D03*
X250749Y222703D03*
Y225852D03*
X253898Y219553D03*
Y222703D03*
X257048Y213254D03*
X250749D03*
X247599D03*
X253898D03*
X247637Y225852D03*
X244450Y232151D03*
X247599D03*
X253898D03*
X257048D03*
X250749Y229002D03*
X253898D03*
X250749Y235301D03*
X253898D03*
X267722Y176791D03*
X264222D03*
X271209Y177524D03*
X270472Y188488D03*
X264118Y188095D03*
X266080Y207262D03*
X262580D03*
X263580Y214593D03*
X267080D03*
X285482Y168102D03*
X273644Y174267D03*
X282975Y172975D03*
X286105Y176085D03*
X289254Y194839D03*
X286105Y185534D03*
Y194839D03*
Y204288D03*
X286106Y210587D03*
X286105Y213721D03*
X289110Y163487D03*
X292260D03*
X295410Y169786D03*
X292404Y176085D03*
X295410Y172936D03*
X289254Y172792D03*
X292260Y169643D03*
X295410Y179235D03*
X292384Y172936D03*
X289254Y176085D03*
Y182385D03*
X292260Y179235D03*
X289111D03*
X292404Y191690D03*
X289254D03*
X292404Y185534D03*
Y194983D03*
X295410Y194839D03*
X295411Y185534D03*
X289254D03*
Y197989D03*
X298714Y210477D03*
X292404Y210587D03*
Y201282D03*
X299667Y201334D03*
X292404Y213737D03*
X289254Y201139D03*
X295410Y210587D03*
X311158Y163487D03*
X308008Y166637D03*
X314307Y163487D03*
X314930Y168140D03*
Y171289D03*
Y177588D03*
X305002Y176085D03*
Y169786D03*
Y172936D03*
X308152Y169786D03*
X311158Y169643D03*
X308152Y172936D03*
Y176085D03*
Y182385D03*
X305002Y179235D03*
X308152D03*
X314930Y180738D03*
Y174439D03*
X308008Y191690D03*
X311158D03*
X308008Y188540D03*
Y185391D03*
Y198133D03*
X314307Y185534D03*
X311158Y188540D03*
X308008Y194839D03*
X311158Y197989D03*
X314307Y194839D03*
Y197989D03*
X308008Y207438D03*
X308152Y204432D03*
X305002D03*
X311158Y210587D03*
X308008Y210731D03*
X305002Y210587D03*
X314307Y201139D03*
Y204288D03*
Y210587D03*
Y213737D03*
G54D39*
X372604Y-455313D03*
Y-430313D03*
X372664Y-223791D03*
Y-198791D03*
X372576Y-177041D03*
Y-152041D03*
X372664Y4481D03*
Y29481D03*
X372604Y51231D03*
Y76231D03*
X372664Y373753D03*
Y398753D03*
X393692Y-481375D03*
X382604Y-455313D03*
X393692Y-456375D03*
X382604Y-430313D03*
X382664Y-223791D03*
Y-198791D03*
X382576Y-177041D03*
Y-152041D03*
X393780Y-128853D03*
Y-103853D03*
X393750Y-82222D03*
Y-57222D03*
X382664Y4481D03*
Y29481D03*
X382604Y51231D03*
Y76231D03*
X393750Y200538D03*
Y225538D03*
Y247050D03*
Y272050D03*
X382664Y373753D03*
X393750Y398810D03*
X382664Y398753D03*
X393750Y423810D03*
X403692Y-481375D03*
Y-456375D03*
X403780Y-128853D03*
Y-103853D03*
X403750Y-82222D03*
D03*
Y-57222D03*
D03*
Y200538D03*
D03*
Y225538D03*
D03*
Y247050D03*
D03*
Y272050D03*
D03*
Y398810D03*
D03*
Y423810D03*
D03*
X413750Y-82222D03*
Y-57222D03*
Y200538D03*
Y225538D03*
Y247050D03*
Y272050D03*
Y398810D03*
Y423810D03*
G54D14*
X3000Y8494D03*
Y28494D03*
Y48494D03*
Y68494D03*
Y88494D03*
Y108494D03*
Y128494D03*
Y148494D03*
Y168494D03*
Y188494D03*
Y208494D03*
Y228494D03*
Y248494D03*
Y268494D03*
Y288494D03*
Y308494D03*
Y342126D03*
Y362126D03*
Y382126D03*
Y402126D03*
Y422126D03*
Y442126D03*
X16626Y195848D03*
X19129D03*
Y193048D03*
X16626D03*
X19129Y204248D03*
X17000Y208017D03*
X16626Y198648D03*
Y201448D03*
X19129Y198648D03*
Y201448D03*
X16626Y204248D03*
X6200Y312900D03*
X13827Y325310D03*
X21250Y206220D03*
X36599Y189016D03*
X37360Y194050D03*
X37823Y198346D03*
X48035Y191535D03*
X47714Y212227D03*
X48940Y204871D03*
X52155Y121218D03*
X60112Y113992D03*
X222402Y169197D03*
X238188Y225852D03*
X228739Y213254D03*
X250749Y159748D03*
X244020Y235518D03*
X244487Y229002D03*
X268510Y179088D03*
X301120Y226421D03*
Y229810D03*
X302687Y275497D03*
X296938Y325700D03*
X311301Y182385D03*
X309521Y226397D03*
Y229786D03*
X314969Y456527D03*
X329297Y134594D03*
Y129890D03*
X321276Y134532D03*
X321349Y130044D03*
X326323Y226349D03*
X317922Y226373D03*
X326323Y229738D03*
X317922Y229762D03*
X373480Y-210223D03*
X370965D03*
Y-206970D03*
X376406Y-206985D03*
X373480Y-206970D03*
X372271Y-213263D03*
X373480Y18049D03*
X370965D03*
X372271Y15009D03*
X370965Y21302D03*
X376406Y21287D03*
X373480Y21302D03*
X372271Y384281D03*
X376406Y390559D03*
X373480Y387321D03*
Y390574D03*
X370965Y387321D03*
Y390574D03*
X383057Y-213263D03*
X381848Y-206970D03*
X384363D03*
Y-210223D03*
X381848D03*
X378922Y-206970D03*
X392081Y-115285D03*
Y-112032D03*
X383057Y15009D03*
X384363Y18049D03*
X381848D03*
Y21302D03*
X384363D03*
X378922D03*
X391950Y214106D03*
Y217359D03*
X378922Y390574D03*
X381848D03*
Y387321D03*
X384363Y390574D03*
Y387321D03*
X383057Y384281D03*
X391950Y412378D03*
Y415631D03*
X394596Y-115285D03*
X393387Y-118325D03*
X404173D03*
X405479Y-115285D03*
X402964D03*
X397522Y-112047D03*
X394596Y-112032D03*
X402964D03*
X405479D03*
X400038D03*
X393357Y211066D03*
X403857D03*
X394450Y217359D03*
Y214106D03*
X396950Y217359D03*
X399450Y217344D03*
X402450Y217359D03*
X404950D03*
X402450Y214106D03*
X404950D03*
X394450Y415631D03*
Y412378D03*
X396950Y415631D03*
X399450Y415616D03*
X393357Y409338D03*
X402450Y415631D03*
X404950D03*
X402450Y412378D03*
X404950D03*
X403857Y409338D03*
X414143Y211066D03*
X415550Y214106D03*
Y217359D03*
X413050D03*
Y214106D03*
X410550Y217359D03*
X408050Y217344D03*
X415550Y412378D03*
Y415631D03*
X413050D03*
Y412378D03*
X410550Y415631D03*
X408050Y415616D03*
X414143Y409338D03*
G54D22*
X23723Y123791D03*
Y120791D03*
X32223Y123791D03*
Y120791D03*
X40723Y123791D03*
Y120791D03*
X49223Y123791D03*
Y121291D03*
X38300Y109200D03*
X60411Y130200D03*
X57470Y426544D03*
X51535D03*
X56482Y450344D03*
X62600Y450700D03*
X71035Y426543D03*
X76770D03*
X142780Y266830D03*
X142500Y345800D03*
X175359Y153286D03*
X178346Y162898D03*
Y172347D03*
Y184945D03*
X181194Y294074D03*
X169669Y399419D03*
X197243Y156599D03*
X187794Y159748D03*
X197243Y178646D03*
X187794Y181795D03*
X197243Y191244D03*
Y197506D03*
Y203805D03*
X184645Y206955D03*
X197243Y200655D03*
Y219553D03*
X194094Y232151D03*
X184645D03*
X185725Y307320D03*
X209842Y156599D03*
X203542Y169197D03*
X212991D03*
X206692D03*
X212991Y181795D03*
X206692Y178646D03*
X209842Y181795D03*
X203542Y191244D03*
X206692D03*
X209842Y184945D03*
X200393Y191244D03*
X203542Y197506D03*
X209842D03*
X203542Y210104D03*
X212991Y206955D03*
Y210104D03*
X209842D03*
X200393D03*
X203542Y200655D03*
X209842D03*
X212991Y219553D03*
X205130Y282000D03*
X204207Y278200D03*
X225552Y156599D03*
X219253Y178646D03*
X225552D03*
Y184945D03*
X219253Y232151D03*
X215600Y316800D03*
X228702Y169197D03*
X231851Y191244D03*
X241300D03*
X235001Y184945D03*
X228702Y191244D03*
X235001Y200655D03*
Y206955D03*
Y219553D03*
X241300Y213254D03*
X238150Y219553D03*
X228702D03*
X238630Y235654D03*
X231851Y232151D03*
X241300D03*
X255492Y152905D03*
X244450Y156599D03*
X253898Y172347D03*
Y178646D03*
X247599Y181795D03*
Y175496D03*
X253898Y191244D03*
Y184945D03*
X247599Y197506D03*
Y188095D03*
Y203805D03*
X253898Y206955D03*
Y200655D03*
X257048Y219553D03*
X250749D03*
Y232151D03*
X257048Y235301D03*
X263294Y153366D03*
X263030Y150846D03*
X268391Y207262D03*
X269391Y214593D03*
X280744Y142070D03*
X283248Y142046D03*
X287725Y363473D03*
X293693Y152232D03*
X290889Y152318D03*
X297372Y196616D03*
X308500Y382100D03*
X339800Y154911D03*
Y159911D03*
Y165911D03*
Y169911D03*
Y176911D03*
Y179911D03*
Y185911D03*
Y189911D03*
X337004Y202113D03*
Y206113D03*
Y210113D03*
G54D37*
X262880Y178977D03*
X308460Y214178D03*
G54D41*
X441000Y-454000D03*
X451000D03*
X441000Y-333400D03*
X451000D03*
X441000Y2000D03*
X451000D03*
X441000Y116000D03*
X451000D03*
G54D15*
X17716Y18465D03*
X45276D03*
X264173Y20040D03*
X291733D03*
X309055Y18465D03*
X336615D03*
G54D31*
X143118Y44803D03*
X194851D03*
G54D32*
X153237Y58583D03*
X165048Y52677D03*
X155205D03*
X161111Y58583D03*
X168985D03*
X172922Y52677D03*
X176859Y58583D03*
X184733D03*
G54D40*
X441000Y-444000D03*
X451000D03*
Y-355000D03*
X441000D03*
Y-323400D03*
X451000D03*
Y-245000D03*
X441000D03*
X451000Y-215000D03*
X441000D03*
Y-136600D03*
X451000D03*
Y-107000D03*
X441000D03*
Y-18000D03*
X451000D03*
X441000Y12000D03*
X451000D03*
Y96000D03*
X441000D03*
Y126000D03*
X451000D03*
Y200000D03*
X441000D03*
X451000Y230000D03*
X441000D03*
Y304000D03*
X451000D03*
Y336000D03*
X441000D03*
Y420000D03*
X451000D03*
G54D44*
X441000Y-126600D03*
X451000D03*
X441000Y-8000D03*
X451000D03*
X441000Y314000D03*
X451000D03*
X441000Y430000D03*
X451000D03*
G54D18*
X24016Y89331D03*
X330315D03*
G54D11*
X-61709Y56192D03*
X-51709D03*
X-61100Y250316D03*
X-61000Y382816D03*
X-51100Y250316D03*
X-51000Y382816D03*
X-35000Y56184D03*
X-25000D03*
X-25100Y250316D03*
X-35100D03*
X-36000Y418816D03*
X-26000D03*
G54D26*
X65945Y297776D03*
G54D36*
X236220Y424016D03*
X301181D03*
G54D33*
X144685Y297776D03*
G54D17*
X22047Y46417D03*
X333466D03*
G54D30*
X105316Y213343D03*
G54D24*
X23819Y349154D03*
X95709Y52244D03*
G54D34*
X182764Y52677D03*
G54D35*
X221142Y24764D03*
G54D10*
X-56709Y43008D03*
X-30000Y43000D03*
G54D29*
X105315Y186571D03*
G54D21*
X27300Y68200D03*
X340639Y432809D03*
G54D20*
X18000Y240900D03*
Y237900D03*
Y249900D03*
Y246900D03*
Y243900D03*
X15688Y259063D03*
X21135Y236587D03*
X21205Y232767D03*
X21135Y240667D03*
Y243737D03*
X24690Y246467D03*
Y251967D03*
X21135Y246837D03*
X21035Y249937D03*
X24690Y249267D03*
X22237Y311481D03*
Y308592D03*
X30638Y311957D03*
Y309068D03*
X22692Y466518D03*
X47440Y308691D03*
X39039Y309044D03*
Y311933D03*
X47440Y312080D03*
X63300Y237600D03*
X68375Y144100D03*
X70580Y167179D03*
X65800Y260875D03*
X81600Y241500D03*
X87500Y237300D03*
X84000Y261375D03*
X103500Y240619D03*
X113590Y245170D03*
X143300Y396400D03*
X146600Y410600D03*
X172550Y398690D03*
X200274Y410960D03*
X225552Y197543D03*
X225441Y282267D03*
X257048Y225890D03*
X292361Y197970D03*
X314985Y397639D03*
Y394639D03*
X332470Y397092D03*
Y394092D03*
X331646Y466536D03*
X339101Y117328D03*
Y121128D03*
X337842Y128533D03*
X334723Y226349D03*
Y229738D03*
X351331Y20788D03*
Y40788D03*
Y60788D03*
Y80788D03*
Y100788D03*
Y120788D03*
Y140788D03*
Y160788D03*
Y180788D03*
Y200788D03*
Y220788D03*
Y240788D03*
Y260788D03*
Y280788D03*
Y300788D03*
Y357531D03*
Y377531D03*
Y397531D03*
Y417531D03*
Y437531D03*
X373420Y-447134D03*
X370905D03*
Y-443881D03*
X373420D03*
X376346Y-447134D03*
X372211Y-440841D03*
X372183Y-162569D03*
X373392Y-168862D03*
X370877D03*
Y-165609D03*
X373392D03*
X376318Y-168862D03*
X373420Y59410D03*
X370905D03*
Y62663D03*
X373420D03*
X376346Y59410D03*
X372211Y65703D03*
X391993Y-473196D03*
Y-469943D03*
X381788Y-443881D03*
X384303D03*
Y-447134D03*
X378862Y-447119D03*
X381788Y-447134D03*
X382997Y-440841D03*
X381760Y-165609D03*
X384275D03*
Y-168862D03*
X378834Y-168847D03*
X381760Y-168862D03*
X382969Y-162569D03*
X391950Y-74043D03*
Y-70790D03*
X381788Y62663D03*
X384303D03*
Y59410D03*
X378862Y59425D03*
X381788Y59410D03*
X382997Y65703D03*
X391950Y255229D03*
Y258482D03*
X405391Y-473196D03*
X399950Y-473181D03*
X402876Y-473196D03*
X394508D03*
X397434D03*
X402876Y-469943D03*
X405391D03*
X404085Y-466903D03*
X393299D03*
X394508Y-469943D03*
X399450Y-74028D03*
X394450Y-74043D03*
Y-70790D03*
X396950Y-74043D03*
X405050D03*
X402550D03*
X405050Y-70790D03*
X402550D03*
X393357Y-67750D03*
X403643D03*
X394450Y255229D03*
X396950D03*
X399450Y255244D03*
X405050Y255229D03*
X402550D03*
X394450Y258482D03*
X393357Y261522D03*
X405050Y258482D03*
X402550D03*
X403643Y261522D03*
X415550Y-70790D03*
Y-74043D03*
X413050D03*
Y-70790D03*
X410550Y-74043D03*
X408050Y-74028D03*
X414143Y-67750D03*
X415550Y255229D03*
X413050D03*
X410550D03*
X408050Y255244D03*
X415550Y258482D03*
X413050D03*
X414143Y261522D03*
G54D38*
X285482Y190187D03*
G54D16*
X9407Y10554D03*
X12900Y105500D03*
X17000Y211541D03*
Y215713D03*
Y219288D03*
X8300Y314700D03*
X22218Y3000D03*
X27323Y25842D03*
X31920Y186610D03*
X25811Y319400D03*
X32000Y326300D03*
X23535Y329990D03*
X34300Y375000D03*
X33100Y392100D03*
X20225Y447671D03*
X42218Y3000D03*
X35044Y35751D03*
X43926Y62248D03*
X45276Y98488D03*
X47294Y184491D03*
X39567Y243133D03*
X40500Y236900D03*
X41574Y255937D03*
X44500Y355500D03*
X38200Y364855D03*
X36600Y408600D03*
X40848Y448440D03*
X62218Y3000D03*
X53000Y41500D03*
X59425Y53075D03*
X50508Y57459D03*
X57500Y75500D03*
X60000D03*
X53267Y109094D03*
X57141Y209341D03*
X59900Y199900D03*
X52000Y230400D03*
X62500Y272500D03*
X60561Y314843D03*
X62458Y390481D03*
X59097Y433502D03*
X63563Y460100D03*
X56476D03*
X76500Y66500D03*
X65928Y76500D03*
X72044Y132312D03*
X71970Y135893D03*
X69195Y135799D03*
X69285Y132321D03*
X67126Y128100D03*
X68335Y141369D03*
X68434Y149506D03*
X68432Y152147D03*
X65301Y187762D03*
X67486Y186414D03*
X72000Y235925D03*
X65801Y253145D03*
X76500Y270700D03*
X74000Y270800D03*
X76284Y280470D03*
X75300Y305150D03*
X69500Y308700D03*
X64567Y306665D03*
X73000Y323400D03*
X68757Y352724D03*
X71906Y355873D03*
X75056Y359023D03*
X65607Y349574D03*
X75056Y377883D03*
X68757Y384182D03*
X65607Y387332D03*
X75018Y381033D03*
X69057Y419700D03*
X78800Y423800D03*
X66297Y433002D03*
X70650Y460100D03*
X77500D03*
X82218Y3000D03*
X91700Y66500D03*
X86500Y75000D03*
X88500Y128000D03*
X81800Y188500D03*
X90900Y222850D03*
X85672Y283985D03*
X81864Y297900D03*
X85600Y298100D03*
X82200Y308700D03*
X82022Y303350D03*
X84126Y311790D03*
X79600Y312000D03*
X85500Y323400D03*
X85600Y335000D03*
X87617Y365322D03*
Y371584D03*
X81355Y365322D03*
Y371584D03*
X86300Y397600D03*
X92001Y450402D03*
X82256Y445577D03*
X85276Y445550D03*
X84823Y460100D03*
X91909Y458275D03*
X102218Y3000D03*
X95400Y66500D03*
X98000Y75500D03*
X108727Y99153D03*
X100000Y98500D03*
X105916Y109952D03*
X101230Y127010D03*
X96400Y137475D03*
X97440Y283590D03*
X105000Y311900D03*
X96457Y323194D03*
X97608Y335534D03*
X100215Y352724D03*
X103383Y349556D03*
X93916Y359023D03*
X97066Y355873D03*
X103383Y387350D03*
X100215Y384182D03*
X93916Y377883D03*
X97066Y381033D03*
X103400Y420000D03*
X95280Y412500D03*
X97156Y450437D03*
X94560Y443287D03*
X100225Y443127D03*
X98996Y458275D03*
X106083D03*
X122218Y3000D03*
X111000Y44600D03*
X122500Y58000D03*
X116560Y88651D03*
X120726Y105000D03*
X115200Y98200D03*
X120626Y123500D03*
X112000D03*
X116200Y115100D03*
X119060Y199695D03*
X118300Y237500D03*
X121720Y265330D03*
X111177Y293471D03*
X118009Y313810D03*
Y311200D03*
X115000Y369500D03*
X127900Y45000D03*
X129575Y57375D03*
X129328Y122500D03*
X126575Y111416D03*
X131700Y131000D03*
X133500Y149385D03*
X124500Y167100D03*
X126300Y176575D03*
X135000Y206900D03*
X128900Y255898D03*
X131216Y280187D03*
X124016Y313784D03*
X135462Y313727D03*
X133100Y358900D03*
X133640Y390524D03*
X124287Y406262D03*
X127300Y392600D03*
X129900Y415583D03*
X138500Y457250D03*
X142218Y3000D03*
X147947Y9800D03*
X146800Y79000D03*
X140869Y89055D03*
X141700Y96929D03*
X140869Y104803D03*
Y120551D03*
Y112677D03*
X142000Y146000D03*
X148400Y155765D03*
X153134Y178572D03*
X146390Y224040D03*
X146000Y216350D03*
X141954Y224274D03*
X142300Y216300D03*
X152400Y293400D03*
X150293Y315493D03*
X140700Y370252D03*
X140300Y395100D03*
X152100Y425700D03*
X145365Y426050D03*
X149041Y458750D03*
X162218Y3000D03*
X165700Y11100D03*
X166719Y75874D03*
X168297Y93976D03*
X164429Y93991D03*
X158873Y93976D03*
X166500Y96400D03*
X158420Y116610D03*
X159700Y112000D03*
X161237Y185815D03*
X161240Y190477D03*
X166361Y209794D03*
X166308Y225189D03*
X155800Y234700D03*
X163690Y268610D03*
X164790Y341100D03*
X163800Y356800D03*
X164318Y389102D03*
X157282D03*
X156900Y385700D03*
X154000Y414750D03*
X165194Y428688D03*
X160852Y460118D03*
X182218Y3000D03*
X173853Y93991D03*
X182925Y84300D03*
X180333Y114292D03*
X178346Y200655D03*
Y213254D03*
Y225852D03*
X174079Y234604D03*
X174400Y249136D03*
X173880Y312430D03*
X182372Y325961D03*
X169200Y349400D03*
X180350Y368650D03*
X177082Y387402D03*
X182750Y426750D03*
X187272Y84472D03*
X191312Y84512D03*
X190200Y100500D03*
X198281Y101286D03*
X187360Y132425D03*
X187794Y213254D03*
X196827Y240349D03*
X185897Y249936D03*
X191583Y261363D03*
X189228Y280655D03*
X190922Y350990D03*
X184118Y387402D03*
X185875Y415051D03*
X189600Y459800D03*
X202218Y3000D03*
X207700Y59100D03*
X213100Y69300D03*
X209500Y92326D03*
X211800Y93870D03*
X209824Y106122D03*
X203600Y117000D03*
X203970Y125500D03*
X211200Y140513D03*
X200393Y169197D03*
X203542Y232151D03*
X198990Y247811D03*
X211265Y267300D03*
X207220Y301180D03*
X207750Y366500D03*
X208360Y384890D03*
X203180Y416371D03*
X211865Y444520D03*
X200000Y455800D03*
X209300Y457700D03*
X222218Y3000D03*
X227547Y74275D03*
X219600Y74000D03*
X215800Y69300D03*
X218600D03*
X224958Y107236D03*
X221500Y125100D03*
X217697Y174852D03*
X219290Y191207D03*
X222402Y206955D03*
Y213254D03*
X223672Y290735D03*
X213610Y308800D03*
X223160Y362600D03*
X222225Y407650D03*
X216725D03*
X218085Y444520D03*
X222200Y458700D03*
X215000Y458600D03*
X242218Y3000D03*
X233000Y47100D03*
X230800Y57613D03*
X239347Y79457D03*
X237280Y107510D03*
X229000Y101000D03*
X242812Y117501D03*
X242800Y132200D03*
X231100Y125600D03*
X235001Y166047D03*
X238150Y169197D03*
X232773Y269532D03*
X228800Y302700D03*
X241400Y328100D03*
X233468Y341046D03*
X233300Y356890D03*
X233600Y371500D03*
X233800Y390118D03*
X228230Y390390D03*
X228200Y459100D03*
X248359Y46559D03*
X248700Y75900D03*
X255750Y77350D03*
X250900Y90900D03*
X254397Y103697D03*
X244987Y103528D03*
X251113Y102919D03*
X252300Y107664D03*
X245391Y99589D03*
X252374Y132159D03*
X244450Y159748D03*
X253388Y273655D03*
X246200Y299700D03*
X243410Y381323D03*
X245300Y445800D03*
X262218Y3000D03*
X267022Y12166D03*
X269095Y34625D03*
X260970Y42441D03*
X268675Y74400D03*
X267168Y93768D03*
X260132D03*
X259759Y103651D03*
X259500Y101100D03*
X268435Y121476D03*
X260269Y207358D03*
X261269Y214657D03*
X266200Y300500D03*
X262930Y325300D03*
X259420Y345930D03*
X265922Y354238D03*
X272100Y396300D03*
X265100Y424000D03*
X266300Y435900D03*
X271500Y446800D03*
X269534Y459061D03*
X282218Y3000D03*
X277000Y41982D03*
X282440Y51941D03*
X274219Y51641D03*
X286000Y67975D03*
X274400Y90019D03*
X279200Y114100D03*
X274500Y131629D03*
X279600Y131400D03*
X285980Y163487D03*
X278155Y176085D03*
X286105Y172936D03*
Y182385D03*
Y197989D03*
Y201139D03*
X286000Y242100D03*
X281889Y287636D03*
X276155Y329999D03*
X276100Y375900D03*
Y381500D03*
X284614Y387136D03*
X281300Y419300D03*
X278200Y408700D03*
X277563Y460028D03*
X283707Y459398D03*
X302218Y3000D03*
X300600Y10591D03*
X288856Y12166D03*
X295402Y48051D03*
X290245Y46978D03*
X300856Y104059D03*
X301151Y108649D03*
X301936Y135797D03*
X294200Y128800D03*
X301507Y195435D03*
X289091Y204331D03*
X289254Y210587D03*
Y213737D03*
X301500Y326500D03*
X298748Y390118D03*
X297399Y397382D03*
X290800Y438300D03*
X291689Y453912D03*
Y456912D03*
Y459912D03*
X313977Y33400D03*
X303575Y54516D03*
X304436Y135897D03*
X307500Y125635D03*
X308008Y163487D03*
X311158Y185534D03*
X314307Y191690D03*
X311158Y194839D03*
Y204288D03*
X314307Y207438D03*
X303940Y212664D03*
X311158Y201139D03*
Y213737D03*
X307500Y256500D03*
X312114Y288439D03*
X315810Y293450D03*
X312315Y293207D03*
X317430Y295665D03*
X314820Y296128D03*
X314201Y302361D03*
X314180Y299440D03*
X303077Y297519D03*
X314132Y310178D03*
X314170Y307020D03*
X309500Y315000D03*
X304000Y305000D03*
X311000Y320500D03*
X315075Y366500D03*
X312226Y382766D03*
X322218Y3000D03*
X319175Y60200D03*
X322600Y76100D03*
X331881Y108593D03*
Y104577D03*
Y112608D03*
X320239Y151075D03*
X323384Y157378D03*
X331405Y157411D03*
X323384Y165378D03*
Y161378D03*
Y169378D03*
Y173378D03*
Y177378D03*
X331405Y177411D03*
Y187411D03*
Y192411D03*
X319601Y201140D03*
X317670Y291430D03*
X330900Y314700D03*
X325038Y356890D03*
X325320Y390118D03*
X325200Y383900D03*
X342218Y3000D03*
X337375Y76600D03*
X342900Y66100D03*
X333278Y151129D03*
X337083Y197000D03*
X336312Y286352D03*
X339700Y295900D03*
X342604Y318773D03*
X335700Y376400D03*
X335500Y363200D03*
X334600Y383300D03*
X334112Y447668D03*
X349290Y337646D03*
X374975Y-435380D03*
X374666Y-218571D03*
X374947Y-157108D03*
X374666Y9701D03*
X374975Y71164D03*
X374666Y378973D03*
X380602Y-435533D03*
X380293Y-218724D03*
X380574Y-157261D03*
X380293Y9548D03*
X380602Y71011D03*
X380293Y378820D03*
X396063Y-461442D03*
X401690Y-461595D03*
X401409Y-123786D03*
X395782Y-123633D03*
G54D42*
X451000Y-345000D03*
X441000D03*
X451000Y-235000D03*
X441000D03*
X451000Y106000D03*
X441000D03*
X451000Y210000D03*
X441000D03*
G54D43*
X451000Y-225000D03*
X441000D03*
X451000Y-117000D03*
X441000D03*
X451000Y220000D03*
X441000D03*
X451000Y326000D03*
X441000D03*
G54D27*
X58654Y290605D03*
X104575Y62369D03*
Y67581D03*
G54D13*
X-30100Y263500D03*
G54D12*
X-56100D03*
X-56000Y396000D03*
X-31000Y432000D03*
%LPC*%
G75*
G54D45*
G01X2010999Y-388000D02*
Y1475775D01*
X-407000D01*
Y-386798D01*
Y-755294D01*
Y-793716D01*
X-368578D01*
X1942346D01*
X2010999D01*
Y-725063D01*
Y-388000D01*
G01X-53307Y-609436D02*
Y-684436D01*
X446693D01*
Y-609436D01*
X-53307D01*
G01X-41307Y-674436D02*
Y-679436D01*
G01X-42764Y-674436D02*
X-39850D01*
G01X-34940Y-679436D02*
X-37474D01*
Y-674436D01*
X-34940D01*
G01X-35954Y-676853D02*
X-37474D01*
G01X-32374Y-674436D02*
Y-679436D01*
X-29840D01*
G01X-26007Y-679603D02*
X-26134Y-679519D01*
Y-679353D01*
X-26007Y-679269D01*
X-25880Y-679353D01*
Y-679519D01*
X-26007Y-679603D01*
G01Y-677353D02*
X-26134Y-677269D01*
Y-677103D01*
X-26007Y-677019D01*
X-25880Y-677103D01*
Y-677269D01*
X-26007Y-677353D01*
G01X-21224Y-681103D02*
X-21857Y-680269D01*
X-22174Y-679436D01*
Y-676103D01*
X-21857Y-675269D01*
X-21224Y-674436D01*
G01X-15807D02*
X-16314Y-674603D01*
X-16694Y-675019D01*
X-16947Y-675519D01*
X-17137Y-676186D01*
X-17200Y-676936D01*
X-17137Y-677686D01*
X-16947Y-678353D01*
X-16694Y-678853D01*
X-16314Y-679269D01*
X-15807Y-679436D01*
X-15300Y-679269D01*
X-14920Y-678853D01*
X-14667Y-678353D01*
X-14477Y-677686D01*
X-14414Y-676936D01*
X-14477Y-676186D01*
X-14667Y-675519D01*
X-14920Y-675019D01*
X-15300Y-674603D01*
X-15807Y-674436D01*
G01X-12100Y-678436D02*
X-11720Y-679019D01*
X-11214Y-679353D01*
X-10644Y-679436D01*
X-10137Y-679353D01*
X-9630Y-678936D01*
X-9314Y-678436D01*
X-9250Y-677936D01*
X-9377Y-677353D01*
X-9820Y-676936D01*
X-10264Y-676769D01*
X-10834D01*
G01X-10264D02*
X-9884Y-676519D01*
X-9567Y-676103D01*
X-9440Y-675603D01*
X-9567Y-675103D01*
X-9884Y-674686D01*
X-10454Y-674436D01*
X-11024Y-674519D01*
X-11594Y-674853D01*
G01X-5290Y-681103D02*
X-4657Y-680269D01*
X-4340Y-679436D01*
Y-676103D01*
X-4657Y-675269D01*
X-5290Y-674436D01*
G01X-1900Y-678436D02*
X-1520Y-679019D01*
X-1014Y-679353D01*
X-444Y-679436D01*
X63Y-679353D01*
X570Y-678936D01*
X886Y-678436D01*
X950Y-677936D01*
X823Y-677353D01*
X380Y-676936D01*
X-64Y-676769D01*
X-634D01*
G01X-64D02*
X316Y-676519D01*
X633Y-676103D01*
X760Y-675603D01*
X633Y-675103D01*
X316Y-674686D01*
X-254Y-674436D01*
X-824Y-674519D01*
X-1394Y-674853D01*
G01X3390Y-675269D02*
X3770Y-674769D01*
X4213Y-674519D01*
X4720Y-674436D01*
X5353Y-674603D01*
X5796Y-675019D01*
X5923Y-675519D01*
X5860Y-676019D01*
X5606Y-676436D01*
X4340Y-677269D01*
X3770Y-677853D01*
X3390Y-678686D01*
X3263Y-679436D01*
X5923D01*
G01X9566D02*
X9693Y-678353D01*
X9883Y-677436D01*
X10136Y-676603D01*
X10453Y-675686D01*
X10960Y-674436D01*
X8426D01*
G01X13970Y-677769D02*
X15616D01*
G01X18690Y-675269D02*
X19070Y-674769D01*
X19513Y-674519D01*
X20020Y-674436D01*
X20653Y-674603D01*
X21096Y-675019D01*
X21223Y-675519D01*
X21160Y-676019D01*
X20906Y-676436D01*
X19640Y-677269D01*
X19070Y-677853D01*
X18690Y-678686D01*
X18563Y-679436D01*
X21223D01*
G01X23600Y-678436D02*
X23980Y-679019D01*
X24486Y-679353D01*
X25056Y-679436D01*
X25563Y-679353D01*
X26070Y-678936D01*
X26386Y-678436D01*
X26450Y-677936D01*
X26323Y-677353D01*
X25880Y-676936D01*
X25436Y-676769D01*
X24866D01*
G01X25436D02*
X25816Y-676519D01*
X26133Y-676103D01*
X26260Y-675603D01*
X26133Y-675103D01*
X25816Y-674686D01*
X25246Y-674436D01*
X24676Y-674519D01*
X24106Y-674853D01*
G01X30853Y-679436D02*
Y-674436D01*
X28510Y-678019D01*
X31676D01*
G01X33800Y-678686D02*
X34180Y-679103D01*
X34623Y-679353D01*
X35193Y-679436D01*
X35763Y-679269D01*
X36206Y-678936D01*
X36523Y-678353D01*
X36586Y-677686D01*
X36460Y-677019D01*
X36143Y-676603D01*
X35700Y-676269D01*
X35256Y-676186D01*
X34813Y-676269D01*
X34243Y-676603D01*
X34433Y-674436D01*
X36143D01*
G01X44190Y-679436D02*
Y-674436D01*
X46596D01*
G01X45710Y-676853D02*
X44190D01*
G01X48910Y-679436D02*
X50493Y-674436D01*
X52076Y-679436D01*
G01X51506Y-677686D02*
X49480D01*
G01X54263Y-679436D02*
X56923Y-674436D01*
G01X54263D02*
X56923Y-679436D01*
G01X60693Y-679603D02*
X60566Y-679519D01*
Y-679353D01*
X60693Y-679269D01*
X60820Y-679353D01*
Y-679519D01*
X60693Y-679603D01*
G01Y-677353D02*
X60566Y-677269D01*
Y-677103D01*
X60693Y-677019D01*
X60820Y-677103D01*
Y-677269D01*
X60693Y-677353D01*
G01X65476Y-681103D02*
X64843Y-680269D01*
X64526Y-679436D01*
Y-676103D01*
X64843Y-675269D01*
X65476Y-674436D01*
G01X70893D02*
X70386Y-674603D01*
X70006Y-675019D01*
X69753Y-675519D01*
X69563Y-676186D01*
X69500Y-676936D01*
X69563Y-677686D01*
X69753Y-678353D01*
X70006Y-678853D01*
X70386Y-679269D01*
X70893Y-679436D01*
X71400Y-679269D01*
X71780Y-678853D01*
X72033Y-678353D01*
X72223Y-677686D01*
X72286Y-676936D01*
X72223Y-676186D01*
X72033Y-675519D01*
X71780Y-675019D01*
X71400Y-674603D01*
X70893Y-674436D01*
G01X74600Y-678436D02*
X74980Y-679019D01*
X75486Y-679353D01*
X76056Y-679436D01*
X76563Y-679353D01*
X77070Y-678936D01*
X77386Y-678436D01*
X77450Y-677936D01*
X77323Y-677353D01*
X76880Y-676936D01*
X76436Y-676769D01*
X75866D01*
G01X76436D02*
X76816Y-676519D01*
X77133Y-676103D01*
X77260Y-675603D01*
X77133Y-675103D01*
X76816Y-674686D01*
X76246Y-674436D01*
X75676Y-674519D01*
X75106Y-674853D01*
G01X81410Y-681103D02*
X82043Y-680269D01*
X82360Y-679436D01*
Y-676103D01*
X82043Y-675269D01*
X81410Y-674436D01*
G01X84800Y-678436D02*
X85180Y-679019D01*
X85686Y-679353D01*
X86256Y-679436D01*
X86763Y-679353D01*
X87270Y-678936D01*
X87586Y-678436D01*
X87650Y-677936D01*
X87523Y-677353D01*
X87080Y-676936D01*
X86636Y-676769D01*
X86066D01*
G01X86636D02*
X87016Y-676519D01*
X87333Y-676103D01*
X87460Y-675603D01*
X87333Y-675103D01*
X87016Y-674686D01*
X86446Y-674436D01*
X85876Y-674519D01*
X85306Y-674853D01*
G01X90216Y-678853D02*
X90660Y-679269D01*
X91166Y-679436D01*
X91673Y-679269D01*
X92116Y-678769D01*
X92433Y-678019D01*
X92560Y-677269D01*
Y-676353D01*
X92433Y-675603D01*
X92116Y-674936D01*
X91736Y-674603D01*
X91293Y-674436D01*
X90786Y-674603D01*
X90406Y-674936D01*
X90153Y-675436D01*
X90026Y-676103D01*
X90153Y-676686D01*
X90470Y-677269D01*
X90850Y-677603D01*
X91293Y-677686D01*
X91800Y-677519D01*
X92180Y-677103D01*
X92560Y-676353D01*
G01X96266Y-679436D02*
X96393Y-678353D01*
X96583Y-677436D01*
X96836Y-676603D01*
X97153Y-675686D01*
X97660Y-674436D01*
X95126D01*
G01X100670Y-677769D02*
X102316D01*
G01X105200Y-678436D02*
X105580Y-679019D01*
X106086Y-679353D01*
X106656Y-679436D01*
X107163Y-679353D01*
X107670Y-678936D01*
X107986Y-678436D01*
X108050Y-677936D01*
X107923Y-677353D01*
X107480Y-676936D01*
X107036Y-676769D01*
X106466D01*
G01X107036D02*
X107416Y-676519D01*
X107733Y-676103D01*
X107860Y-675603D01*
X107733Y-675103D01*
X107416Y-674686D01*
X106846Y-674436D01*
X106276Y-674519D01*
X105706Y-674853D01*
G01X110490Y-677353D02*
X110933Y-676769D01*
X111313Y-676436D01*
X111820Y-676269D01*
X112263Y-676436D01*
X112580Y-676769D01*
X112833Y-677269D01*
X112896Y-677853D01*
X112833Y-678353D01*
X112580Y-678853D01*
X112200Y-679269D01*
X111756Y-679436D01*
X111250Y-679269D01*
X110806Y-678769D01*
X110553Y-678019D01*
X110490Y-677186D01*
X110616Y-676103D01*
X110806Y-675519D01*
X111123Y-674936D01*
X111566Y-674519D01*
X112010Y-674436D01*
X112453Y-674603D01*
X112770Y-675019D01*
G01X116793Y-679436D02*
Y-674436D01*
X116033Y-675436D01*
G01Y-679436D02*
X117553D01*
G01X122653D02*
Y-674436D01*
X120310Y-678019D01*
X123476D01*
G01X141693Y-609436D02*
Y-684436D01*
G01Y-659436D02*
X244693D01*
Y-634436D01*
G01X141693D02*
X244693D01*
G01X246693Y-609436D02*
Y-684436D01*
G01X244693Y-609436D02*
Y-684436D01*
G01X252200Y-669436D02*
Y-664436D01*
X253466D01*
X253973Y-664686D01*
X254353Y-665019D01*
X254670Y-665519D01*
X254923Y-666103D01*
X254986Y-666936D01*
X254923Y-667769D01*
X254670Y-668353D01*
X254353Y-668853D01*
X253973Y-669186D01*
X253466Y-669436D01*
X252200D01*
G01X257110D02*
X258693Y-664436D01*
X260276Y-669436D01*
G01X259706Y-667686D02*
X257680D01*
G01X263793Y-664436D02*
Y-669436D01*
G01X262336Y-664436D02*
X265250D01*
G01X270160Y-669436D02*
X267626D01*
Y-664436D01*
X270160D01*
G01X269146Y-666853D02*
X267626D01*
G01X273993Y-669603D02*
X273866Y-669519D01*
Y-669353D01*
X273993Y-669269D01*
X274120Y-669353D01*
Y-669519D01*
X273993Y-669603D01*
G01Y-667353D02*
X273866Y-667269D01*
Y-667103D01*
X273993Y-667019D01*
X274120Y-667103D01*
Y-667269D01*
X273993Y-667353D01*
G01X246693Y-659436D02*
X446693D01*
G01X252326Y-644436D02*
Y-639436D01*
X253846D01*
X254353Y-639686D01*
X254733Y-640269D01*
X254860Y-640936D01*
X254733Y-641603D01*
X254416Y-642103D01*
X253846Y-642353D01*
X252326D01*
G01X257553Y-644603D02*
X259833Y-639436D01*
G01X262336Y-644436D02*
Y-639436D01*
X265250Y-644436D01*
Y-639436D01*
G01X268893Y-644603D02*
X268766Y-644519D01*
Y-644353D01*
X268893Y-644269D01*
X269020Y-644353D01*
Y-644519D01*
X268893Y-644603D01*
G01Y-642353D02*
X268766Y-642269D01*
Y-642103D01*
X268893Y-642019D01*
X269020Y-642103D01*
Y-642269D01*
X268893Y-642353D01*
G01X246693Y-634436D02*
X446693D01*
G01X252326Y-619436D02*
Y-614436D01*
X253846D01*
X254353Y-614686D01*
X254733Y-615269D01*
X254860Y-615936D01*
X254733Y-616603D01*
X254416Y-617103D01*
X253846Y-617353D01*
X252326D01*
G01X257426Y-619436D02*
Y-614436D01*
X259010D01*
X259516Y-614686D01*
X259833Y-615019D01*
X259960Y-615686D01*
X259833Y-616353D01*
X259453Y-616769D01*
X259010Y-617019D01*
X257426D01*
G01X259010D02*
X259960Y-619436D01*
G01X263793D02*
X263286Y-619353D01*
X262843Y-619019D01*
X262463Y-618519D01*
X262210Y-617936D01*
X262083Y-617269D01*
Y-616603D01*
X262210Y-615936D01*
X262463Y-615353D01*
X262843Y-614853D01*
X263286Y-614519D01*
X263793Y-614436D01*
X264300Y-614519D01*
X264743Y-614853D01*
X265123Y-615353D01*
X265376Y-615936D01*
X265503Y-616603D01*
Y-617269D01*
X265376Y-617936D01*
X265123Y-618519D01*
X264743Y-619019D01*
X264300Y-619353D01*
X263793Y-619436D01*
G01X267626Y-618436D02*
X267943Y-618936D01*
X268323Y-619269D01*
X268766Y-619436D01*
X269273Y-619269D01*
X269653Y-618936D01*
X270033Y-618436D01*
X270160Y-617769D01*
Y-614436D01*
G01X275260Y-619436D02*
X272726D01*
Y-614436D01*
X275260D01*
G01X274246Y-616853D02*
X272726D01*
G01X280486Y-614853D02*
X280106Y-614603D01*
X279663Y-614436D01*
X279156D01*
X278586Y-614686D01*
X278143Y-615103D01*
X277826Y-615603D01*
X277573Y-616436D01*
X277510Y-617186D01*
X277636Y-617936D01*
X277826Y-618436D01*
X278206Y-618936D01*
X278650Y-619269D01*
X279093Y-619436D01*
X279536D01*
X279980Y-619269D01*
X280360Y-619019D01*
X280676Y-618686D01*
G01X284193Y-614436D02*
Y-619436D01*
G01X282736Y-614436D02*
X285650D01*
G01X289293Y-619603D02*
X289166Y-619519D01*
Y-619353D01*
X289293Y-619269D01*
X289420Y-619353D01*
Y-619519D01*
X289293Y-619603D01*
G01Y-617353D02*
X289166Y-617269D01*
Y-617103D01*
X289293Y-617019D01*
X289420Y-617103D01*
Y-617269D01*
X289293Y-617353D01*
G01X361693Y-659436D02*
Y-684436D01*
G01X364326Y-661936D02*
Y-666936D01*
X366860D01*
G01X369933Y-661936D02*
X371453D01*
G01X370693D02*
Y-666936D01*
G01X369933D02*
X371453D01*
G01X376300Y-664269D02*
X376553Y-664019D01*
X376743Y-663603D01*
X376870Y-663019D01*
X376743Y-662519D01*
X376490Y-662186D01*
X376046Y-661936D01*
X374336D01*
Y-666936D01*
X376426D01*
X376870Y-666603D01*
X377123Y-666103D01*
X377250Y-665519D01*
X377123Y-664936D01*
X376743Y-664436D01*
X376300Y-664269D01*
X374336D01*
G01X380893Y-667103D02*
X380766Y-667019D01*
Y-666853D01*
X380893Y-666769D01*
X381020Y-666853D01*
Y-667019D01*
X380893Y-667103D01*
G01Y-664853D02*
X380766Y-664769D01*
Y-664603D01*
X380893Y-664519D01*
X381020Y-664603D01*
Y-664769D01*
X380893Y-664853D01*
G01X404693Y-659436D02*
Y-684436D01*
G01Y-634436D02*
Y-659436D01*
G01X412706Y-687603D02*
X412813Y-687478D01*
X412893Y-687269D01*
X412946Y-686978D01*
X412893Y-686728D01*
X412786Y-686561D01*
X412600Y-686436D01*
X411880D01*
Y-688936D01*
X412760D01*
X412946Y-688769D01*
X413053Y-688519D01*
X413106Y-688228D01*
X413053Y-687936D01*
X412893Y-687686D01*
X412706Y-687603D01*
X411880D01*
G01X415173Y-688936D02*
Y-687269D01*
G01Y-687561D02*
X415066Y-687394D01*
X414906Y-687311D01*
X414720Y-687269D01*
X414533Y-687353D01*
X414373Y-687519D01*
X414266Y-687769D01*
X414213Y-688103D01*
X414266Y-688436D01*
X414373Y-688686D01*
X414533Y-688853D01*
X414720Y-688936D01*
X414906Y-688894D01*
X415066Y-688769D01*
X415173Y-688603D01*
G01X416493Y-688644D02*
X416626Y-688811D01*
X416813Y-688936D01*
X416973D01*
X417133Y-688853D01*
X417240Y-688728D01*
X417293Y-688561D01*
X417266Y-688311D01*
X417160Y-688186D01*
X416680Y-687936D01*
X416573Y-687644D01*
X416626Y-687436D01*
X416733Y-687311D01*
X416893Y-687269D01*
X417053Y-687311D01*
X417213Y-687436D01*
G01X418693Y-687811D02*
X419546D01*
X419466Y-687519D01*
X419333Y-687353D01*
X419146Y-687269D01*
X418960Y-687311D01*
X418800Y-687436D01*
X418693Y-687728D01*
X418640Y-687978D01*
Y-688228D01*
X418693Y-688478D01*
X418826Y-688728D01*
X418986Y-688894D01*
X419173Y-688936D01*
X419360Y-688853D01*
X419546Y-688603D01*
G01X420813Y-688936D02*
Y-686436D01*
G01Y-687686D02*
X420946Y-687436D01*
X421106Y-687311D01*
X421266Y-687269D01*
X421506Y-687353D01*
X421666Y-687519D01*
X421773Y-687811D01*
Y-688144D01*
X421720Y-688478D01*
X421613Y-688728D01*
X421426Y-688894D01*
X421266Y-688936D01*
X421106Y-688894D01*
X420946Y-688769D01*
X420813Y-688561D01*
G01X423493Y-688936D02*
X423333Y-688894D01*
X423173Y-688728D01*
X423066Y-688436D01*
X423013Y-688103D01*
X423066Y-687769D01*
X423173Y-687478D01*
X423333Y-687311D01*
X423493Y-687269D01*
X423653Y-687311D01*
X423813Y-687478D01*
X423920Y-687769D01*
X423946Y-688103D01*
X423920Y-688436D01*
X423813Y-688728D01*
X423653Y-688894D01*
X423493Y-688936D01*
G01X426173D02*
Y-687269D01*
G01Y-687561D02*
X426066Y-687394D01*
X425906Y-687311D01*
X425720Y-687269D01*
X425533Y-687353D01*
X425373Y-687519D01*
X425266Y-687769D01*
X425213Y-688103D01*
X425266Y-688436D01*
X425373Y-688686D01*
X425533Y-688853D01*
X425720Y-688936D01*
X425906Y-688894D01*
X426066Y-688769D01*
X426173Y-688603D01*
G01X427520Y-688936D02*
Y-687269D01*
G01Y-687603D02*
X427653Y-687436D01*
X427786Y-687311D01*
X427973Y-687269D01*
X428106Y-687311D01*
X428266Y-687436D01*
G01X430573Y-686436D02*
Y-688936D01*
G01Y-688561D02*
X430466Y-688769D01*
X430306Y-688894D01*
X430120Y-688936D01*
X429906Y-688853D01*
X429746Y-688644D01*
X429640Y-688394D01*
X429613Y-688103D01*
X429640Y-687811D01*
X429746Y-687561D01*
X429906Y-687353D01*
X430120Y-687269D01*
X430306Y-687311D01*
X430440Y-687394D01*
X430573Y-687561D01*
G01X433960Y-688936D02*
Y-686436D01*
X434626D01*
X434840Y-686561D01*
X434973Y-686728D01*
X435026Y-687061D01*
X434973Y-687394D01*
X434813Y-687603D01*
X434626Y-687728D01*
X433960D01*
G01X434626D02*
X435026Y-688936D01*
G01X436293Y-687811D02*
X437146D01*
X437066Y-687519D01*
X436933Y-687353D01*
X436746Y-687269D01*
X436560Y-687311D01*
X436400Y-687436D01*
X436293Y-687728D01*
X436240Y-687978D01*
Y-688228D01*
X436293Y-688478D01*
X436426Y-688728D01*
X436586Y-688894D01*
X436773Y-688936D01*
X436960Y-688853D01*
X437146Y-688603D01*
G01X438413Y-687269D02*
X438893Y-688936D01*
X439373Y-687269D01*
G01X441093Y-689019D02*
X441040Y-688978D01*
Y-688894D01*
X441093Y-688853D01*
X441146Y-688894D01*
Y-688978D01*
X441093Y-689019D01*
G01X443613Y-688936D02*
Y-686436D01*
X442626Y-688228D01*
X443960D01*
G01X444826Y-688936D02*
X445493Y-686436D01*
X446160Y-688936D01*
G01X445920Y-688061D02*
X445066D01*
G01X408593Y-661936D02*
Y-666936D01*
G01X407136Y-661936D02*
X410050D01*
G01X413693Y-666936D02*
X413313Y-666853D01*
X412933Y-666519D01*
X412680Y-665936D01*
X412553Y-665269D01*
X412680Y-664603D01*
X412933Y-664019D01*
X413313Y-663686D01*
X413693Y-663603D01*
X414073Y-663686D01*
X414453Y-664019D01*
X414706Y-664603D01*
X414770Y-665269D01*
X414706Y-665936D01*
X414453Y-666519D01*
X414073Y-666853D01*
X413693Y-666936D01*
G01X418793D02*
X418413Y-666853D01*
X418033Y-666519D01*
X417780Y-665936D01*
X417653Y-665269D01*
X417780Y-664603D01*
X418033Y-664019D01*
X418413Y-663686D01*
X418793Y-663603D01*
X419173Y-663686D01*
X419553Y-664019D01*
X419806Y-664603D01*
X419870Y-665269D01*
X419806Y-665936D01*
X419553Y-666519D01*
X419173Y-666853D01*
X418793Y-666936D01*
G01X423893D02*
Y-661936D01*
G01X428993Y-667103D02*
X428866Y-667019D01*
Y-666853D01*
X428993Y-666769D01*
X429120Y-666853D01*
Y-667019D01*
X428993Y-667103D01*
G01Y-664853D02*
X428866Y-664769D01*
Y-664603D01*
X428993Y-664519D01*
X429120Y-664603D01*
Y-664769D01*
X428993Y-664853D01*
G01X407326Y-641936D02*
Y-636936D01*
X408910D01*
X409416Y-637186D01*
X409733Y-637519D01*
X409860Y-638186D01*
X409733Y-638853D01*
X409353Y-639269D01*
X408910Y-639519D01*
X407326D01*
G01X408910D02*
X409860Y-641936D01*
G01X414960D02*
X412426D01*
Y-636936D01*
X414960D01*
G01X413946Y-639353D02*
X412426D01*
G01X417210Y-636936D02*
X418793Y-641936D01*
X420376Y-636936D01*
G01X423893Y-642103D02*
X423766Y-642019D01*
Y-641853D01*
X423893Y-641769D01*
X424020Y-641853D01*
Y-642019D01*
X423893Y-642103D01*
G01Y-639853D02*
X423766Y-639769D01*
Y-639603D01*
X423893Y-639519D01*
X424020Y-639603D01*
Y-639769D01*
X423893Y-639853D01*
G01X2010999Y-388000D02*
Y1475775D01*
X-407000D01*
Y-386798D01*
Y-755294D01*
Y-793716D01*
X-368578D01*
X1942346D01*
X2010999D01*
Y-725063D01*
Y-388000D01*
G01X-42602Y-671096D02*
X-41975Y-671621D01*
X-41270Y-671936D01*
X-40644D01*
X-40017Y-671621D01*
X-39547Y-671096D01*
X-39312Y-670361D01*
X-39469Y-669626D01*
X-39860Y-668996D01*
X-40565Y-668576D01*
X-41505Y-668366D01*
X-42054Y-667946D01*
X-42289Y-667211D01*
X-42132Y-666476D01*
X-41740Y-665951D01*
X-41192Y-665636D01*
X-40644D01*
X-40095Y-665846D01*
X-39625Y-666371D01*
G01X-36302Y-671936D02*
Y-665636D01*
G01X-33012D02*
Y-671936D01*
G01Y-668786D02*
X-36302D01*
G01X-29297Y-665636D02*
X-27417D01*
G01X-28357D02*
Y-671936D01*
G01X-29297D02*
X-27417D01*
G01X-20490D02*
X-23624D01*
Y-665636D01*
X-20490D01*
G01X-21744Y-668681D02*
X-23624D01*
G01X-17559Y-671936D02*
Y-665636D01*
X-13955Y-671936D01*
Y-665636D01*
G01X-9614Y-673091D02*
X-9300Y-671726D01*
G01X-3157Y-665636D02*
Y-671936D01*
G01X-4959Y-665636D02*
X-1355D01*
G01X1185Y-671936D02*
X3143Y-665636D01*
X5101Y-671936D01*
G01X4396Y-669731D02*
X1890D01*
G01X8503Y-665636D02*
X10383D01*
G01X9443D02*
Y-671936D01*
G01X8503D02*
X10383D01*
G01X13393Y-665636D02*
X14490Y-671936D01*
X15743Y-665636D01*
X16996Y-671936D01*
X18093Y-665636D01*
G01X20085Y-671936D02*
X22043Y-665636D01*
X24001Y-671936D01*
G01X23296Y-669731D02*
X20790D01*
G01X26541Y-671936D02*
Y-665636D01*
X30145Y-671936D01*
Y-665636D01*
G01X39376Y-671936D02*
Y-665636D01*
X41335D01*
X41961Y-665951D01*
X42353Y-666371D01*
X42510Y-667211D01*
X42353Y-668051D01*
X41883Y-668576D01*
X41335Y-668891D01*
X39376D01*
G01X41335D02*
X42510Y-671936D01*
G01X47243Y-672146D02*
X47086Y-672041D01*
Y-671831D01*
X47243Y-671726D01*
X47400Y-671831D01*
Y-672041D01*
X47243Y-672146D01*
G01X53543Y-671936D02*
X52916Y-671831D01*
X52368Y-671411D01*
X51898Y-670781D01*
X51585Y-670046D01*
X51428Y-669206D01*
Y-668366D01*
X51585Y-667526D01*
X51898Y-666791D01*
X52368Y-666161D01*
X52916Y-665741D01*
X53543Y-665636D01*
X54170Y-665741D01*
X54718Y-666161D01*
X55188Y-666791D01*
X55501Y-667526D01*
X55658Y-668366D01*
Y-669206D01*
X55501Y-670046D01*
X55188Y-670781D01*
X54718Y-671411D01*
X54170Y-671831D01*
X53543Y-671936D01*
G01X59843Y-672146D02*
X59686Y-672041D01*
Y-671831D01*
X59843Y-671726D01*
X60000Y-671831D01*
Y-672041D01*
X59843Y-672146D01*
G01X67866Y-666161D02*
X67396Y-665846D01*
X66848Y-665636D01*
X66221D01*
X65516Y-665951D01*
X64968Y-666476D01*
X64576Y-667106D01*
X64263Y-668156D01*
X64185Y-669101D01*
X64341Y-670046D01*
X64576Y-670676D01*
X65046Y-671306D01*
X65595Y-671726D01*
X66143Y-671936D01*
X66691D01*
X67240Y-671726D01*
X67710Y-671411D01*
X68101Y-670991D01*
G01X72443Y-672146D02*
X72286Y-672041D01*
Y-671831D01*
X72443Y-671726D01*
X72600Y-671831D01*
Y-672041D01*
X72443Y-672146D01*
G01X-42680Y-661936D02*
Y-655636D01*
G01X-39704D02*
X-42680Y-659521D01*
G01X-39234Y-661936D02*
X-41349Y-657736D01*
G01X-36380Y-655636D02*
Y-660151D01*
X-36067Y-661096D01*
X-35440Y-661726D01*
X-34657Y-661936D01*
X-33874Y-661726D01*
X-33247Y-661096D01*
X-32934Y-660151D01*
Y-655636D01*
G01X-26790Y-661936D02*
X-29924D01*
Y-655636D01*
X-26790D01*
G01X-28044Y-658681D02*
X-29924D01*
G01X-22997Y-655636D02*
X-21117D01*
G01X-22057D02*
Y-661936D01*
G01X-22997D02*
X-21117D01*
G01X-11102Y-661096D02*
X-10475Y-661621D01*
X-9770Y-661936D01*
X-9144D01*
X-8517Y-661621D01*
X-8047Y-661096D01*
X-7812Y-660361D01*
X-7969Y-659626D01*
X-8360Y-658996D01*
X-9065Y-658576D01*
X-10005Y-658366D01*
X-10554Y-657946D01*
X-10789Y-657211D01*
X-10632Y-656476D01*
X-10240Y-655951D01*
X-9692Y-655636D01*
X-9144D01*
X-8595Y-655846D01*
X-8125Y-656371D01*
G01X-4802Y-661936D02*
Y-655636D01*
G01X-1512D02*
Y-661936D01*
G01Y-658786D02*
X-4802D01*
G01X1185Y-661936D02*
X3143Y-655636D01*
X5101Y-661936D01*
G01X4396Y-659731D02*
X1890D01*
G01X7641Y-661936D02*
Y-655636D01*
X11245Y-661936D01*
Y-655636D01*
G01X20398Y-661936D02*
Y-655636D01*
G01X23688D02*
Y-661936D01*
G01Y-658786D02*
X20398D01*
G01X26698Y-661096D02*
X27325Y-661621D01*
X28030Y-661936D01*
X28656D01*
X29283Y-661621D01*
X29753Y-661096D01*
X29988Y-660361D01*
X29831Y-659626D01*
X29440Y-658996D01*
X28735Y-658576D01*
X27795Y-658366D01*
X27246Y-657946D01*
X27011Y-657211D01*
X27168Y-656476D01*
X27560Y-655951D01*
X28108Y-655636D01*
X28656D01*
X29205Y-655846D01*
X29675Y-656371D01*
G01X33703Y-655636D02*
X35583D01*
G01X34643D02*
Y-661936D01*
G01X33703D02*
X35583D01*
G01X38985D02*
X40943Y-655636D01*
X42901Y-661936D01*
G01X42196Y-659731D02*
X39690D01*
G01X45441Y-661936D02*
Y-655636D01*
X49045Y-661936D01*
Y-655636D01*
G01X54013Y-658786D02*
X55580D01*
Y-660676D01*
X55110Y-661306D01*
X54561Y-661726D01*
X53778Y-661936D01*
X52995Y-661726D01*
X52446Y-661306D01*
X51976Y-660676D01*
X51663Y-659941D01*
X51506Y-659101D01*
Y-658366D01*
X51663Y-657736D01*
X51976Y-657001D01*
X52446Y-656371D01*
X52916Y-655951D01*
X53543Y-655636D01*
X54091D01*
X54718Y-655846D01*
X55188Y-656266D01*
G01X59686Y-663091D02*
X60000Y-661726D01*
G01X66143Y-655636D02*
Y-661936D01*
G01X64341Y-655636D02*
X67945D01*
G01X70485Y-661936D02*
X72443Y-655636D01*
X74401Y-661936D01*
G01X73696Y-659731D02*
X71190D01*
G01X78743Y-661936D02*
X78116Y-661831D01*
X77568Y-661411D01*
X77098Y-660781D01*
X76785Y-660046D01*
X76628Y-659206D01*
Y-658366D01*
X76785Y-657526D01*
X77098Y-656791D01*
X77568Y-656161D01*
X78116Y-655741D01*
X78743Y-655636D01*
X79370Y-655741D01*
X79918Y-656161D01*
X80388Y-656791D01*
X80701Y-657526D01*
X80858Y-658366D01*
Y-659206D01*
X80701Y-660046D01*
X80388Y-660781D01*
X79918Y-661411D01*
X79370Y-661831D01*
X78743Y-661936D01*
G01X91343D02*
Y-659101D01*
X89776Y-655636D01*
G01X92910D02*
X91343Y-659101D01*
G01X95920Y-655636D02*
Y-660151D01*
X96233Y-661096D01*
X96860Y-661726D01*
X97643Y-661936D01*
X98426Y-661726D01*
X99053Y-661096D01*
X99366Y-660151D01*
Y-655636D01*
G01X101985Y-661936D02*
X103943Y-655636D01*
X105901Y-661936D01*
G01X105196Y-659731D02*
X102690D01*
G01X108441Y-661936D02*
Y-655636D01*
X112045Y-661936D01*
Y-655636D01*
G01X-42759Y-651936D02*
Y-645636D01*
X-39155Y-651936D01*
Y-645636D01*
G01X-34657Y-651936D02*
X-35284Y-651831D01*
X-35832Y-651411D01*
X-36302Y-650781D01*
X-36615Y-650046D01*
X-36772Y-649206D01*
Y-648366D01*
X-36615Y-647526D01*
X-36302Y-646791D01*
X-35832Y-646161D01*
X-35284Y-645741D01*
X-34657Y-645636D01*
X-34030Y-645741D01*
X-33482Y-646161D01*
X-33012Y-646791D01*
X-32699Y-647526D01*
X-32542Y-648366D01*
Y-649206D01*
X-32699Y-650046D01*
X-33012Y-650781D01*
X-33482Y-651411D01*
X-34030Y-651831D01*
X-34657Y-651936D01*
G01X-28357Y-652146D02*
X-28514Y-652041D01*
Y-651831D01*
X-28357Y-651726D01*
X-28200Y-651831D01*
Y-652041D01*
X-28357Y-652146D01*
G01X-22057Y-651936D02*
Y-645636D01*
X-22997Y-646896D01*
G01Y-651936D02*
X-21117D01*
G01X-15757D02*
X-15209Y-651831D01*
X-14582Y-651516D01*
X-14190Y-650991D01*
X-14034Y-650256D01*
X-14190Y-649521D01*
X-14660Y-648891D01*
X-15365Y-648576D01*
X-16149D01*
X-16619Y-648366D01*
X-17010Y-647841D01*
X-17167Y-647106D01*
X-16932Y-646371D01*
X-16384Y-645846D01*
X-15757Y-645636D01*
X-15130Y-645846D01*
X-14582Y-646371D01*
X-14347Y-647106D01*
X-14504Y-647841D01*
X-14895Y-648366D01*
X-15365Y-648576D01*
X-16149D01*
X-16854Y-648891D01*
X-17324Y-649521D01*
X-17480Y-650256D01*
X-17324Y-650991D01*
X-16932Y-651516D01*
X-16305Y-651831D01*
X-15757Y-651936D01*
G01X-9457D02*
X-8909Y-651831D01*
X-8282Y-651516D01*
X-7890Y-650991D01*
X-7734Y-650256D01*
X-7890Y-649521D01*
X-8360Y-648891D01*
X-9065Y-648576D01*
X-9849D01*
X-10319Y-648366D01*
X-10710Y-647841D01*
X-10867Y-647106D01*
X-10632Y-646371D01*
X-10084Y-645846D01*
X-9457Y-645636D01*
X-8830Y-645846D01*
X-8282Y-646371D01*
X-8047Y-647106D01*
X-8204Y-647841D01*
X-8595Y-648366D01*
X-9065Y-648576D01*
X-9849D01*
X-10554Y-648891D01*
X-11024Y-649521D01*
X-11180Y-650256D01*
X-11024Y-650991D01*
X-10632Y-651516D01*
X-10005Y-651831D01*
X-9457Y-651936D01*
G01X-3314Y-653091D02*
X-3000Y-651726D01*
G01X793Y-645636D02*
X1890Y-651936D01*
X3143Y-645636D01*
X4396Y-651936D01*
X5493Y-645636D01*
G01X11010Y-651936D02*
X7876D01*
Y-645636D01*
X11010D01*
G01X9756Y-648681D02*
X7876D01*
G01X13941Y-651936D02*
Y-645636D01*
X17545Y-651936D01*
Y-645636D01*
G01X26698Y-651936D02*
Y-645636D01*
G01X29988D02*
Y-651936D01*
G01Y-648786D02*
X26698D01*
G01X32293Y-645636D02*
X33390Y-651936D01*
X34643Y-645636D01*
X35896Y-651936D01*
X36993Y-645636D01*
G01X38985Y-651936D02*
X40943Y-645636D01*
X42901Y-651936D01*
G01X42196Y-649731D02*
X39690D01*
G01X52055Y-646686D02*
X52525Y-646056D01*
X53073Y-645741D01*
X53700Y-645636D01*
X54483Y-645846D01*
X55031Y-646371D01*
X55188Y-647001D01*
X55110Y-647631D01*
X54796Y-648156D01*
X53230Y-649206D01*
X52525Y-649941D01*
X52055Y-650991D01*
X51898Y-651936D01*
X55188D01*
G01X58041D02*
Y-645636D01*
X61645Y-651936D01*
Y-645636D01*
G01X64420Y-651936D02*
Y-645636D01*
X65986D01*
X66613Y-645951D01*
X67083Y-646371D01*
X67475Y-647001D01*
X67788Y-647736D01*
X67866Y-648786D01*
X67788Y-649836D01*
X67475Y-650571D01*
X67083Y-651201D01*
X66613Y-651621D01*
X65986Y-651936D01*
X64420D01*
G01X77176D02*
Y-645636D01*
X79135D01*
X79761Y-645951D01*
X80153Y-646371D01*
X80310Y-647211D01*
X80153Y-648051D01*
X79683Y-648576D01*
X79135Y-648891D01*
X77176D01*
G01X79135D02*
X80310Y-651936D01*
G01X83320D02*
Y-645636D01*
X84886D01*
X85513Y-645951D01*
X85983Y-646371D01*
X86375Y-647001D01*
X86688Y-647736D01*
X86766Y-648786D01*
X86688Y-649836D01*
X86375Y-650571D01*
X85983Y-651201D01*
X85513Y-651621D01*
X84886Y-651936D01*
X83320D01*
G01X91343Y-652146D02*
X91186Y-652041D01*
Y-651831D01*
X91343Y-651726D01*
X91500Y-651831D01*
Y-652041D01*
X91343Y-652146D01*
G01X-18657Y-639236D02*
X-21177Y-638819D01*
X-23382Y-637153D01*
X-25272Y-634653D01*
X-26532Y-631736D01*
X-27162Y-628403D01*
Y-625069D01*
X-26532Y-621736D01*
X-25272Y-618819D01*
X-23382Y-616320D01*
X-21177Y-614653D01*
X-18657Y-614236D01*
X-16137Y-614653D01*
X-13932Y-616320D01*
X-12042Y-618819D01*
X-10782Y-621736D01*
X-10152Y-625069D01*
Y-628403D01*
X-10782Y-631736D01*
X-12042Y-634653D01*
X-13932Y-637153D01*
X-16137Y-638819D01*
X-18657Y-639236D01*
G01X-16137Y-632569D02*
X-12357Y-639236D01*
G01X1188Y-622570D02*
Y-634236D01*
X2448Y-637153D01*
X4338Y-638819D01*
X6543Y-639236D01*
X8748Y-638819D01*
X10638Y-637153D01*
X11898Y-634236D01*
G01Y-639236D02*
Y-622570D01*
G01X37413Y-639236D02*
Y-622570D01*
G01Y-625486D02*
X36153Y-623820D01*
X34263Y-622986D01*
X32058Y-622570D01*
X29853Y-623403D01*
X27963Y-625069D01*
X26703Y-627570D01*
X26073Y-630903D01*
X26703Y-634236D01*
X27963Y-636737D01*
X29853Y-638403D01*
X32058Y-639236D01*
X34263Y-638819D01*
X36153Y-637570D01*
X37413Y-635903D01*
G01X51588Y-639236D02*
Y-622570D01*
G01Y-626736D02*
X52848Y-624653D01*
X54738Y-622986D01*
X57258Y-622570D01*
X59463Y-622986D01*
X61353Y-624653D01*
X62298Y-627570D01*
Y-639236D01*
G01X82143Y-614236D02*
Y-639236D01*
G01X77733Y-622570D02*
X86553D01*
G01X113013Y-639236D02*
Y-622570D01*
G01Y-625486D02*
X111753Y-623820D01*
X109863Y-622986D01*
X107658Y-622570D01*
X105453Y-623403D01*
X103563Y-625069D01*
X102303Y-627570D01*
X101673Y-630903D01*
X102303Y-634236D01*
X103563Y-636737D01*
X105453Y-638403D01*
X107658Y-639236D01*
X109863Y-638819D01*
X111753Y-637570D01*
X113013Y-635903D01*
G01X152693Y-618936D02*
Y-626936D01*
X156693D01*
G01X164493D02*
Y-621603D01*
G01Y-622536D02*
X164093Y-622003D01*
X163493Y-621736D01*
X162793Y-621603D01*
X162093Y-621869D01*
X161493Y-622403D01*
X161093Y-623203D01*
X160893Y-624269D01*
X161093Y-625336D01*
X161493Y-626136D01*
X162093Y-626669D01*
X162793Y-626936D01*
X163493Y-626803D01*
X164093Y-626403D01*
X164493Y-625870D01*
G01X168593Y-629336D02*
X169193Y-629603D01*
X169993Y-629336D01*
X170493Y-628803D01*
X170893Y-628136D01*
X171493Y-626003D01*
X172793Y-621603D01*
G01X169593D02*
X171493Y-626003D01*
G01X177193Y-623336D02*
X180393D01*
X180093Y-622403D01*
X179593Y-621869D01*
X178893Y-621603D01*
X178193Y-621736D01*
X177593Y-622136D01*
X177193Y-623069D01*
X176993Y-623870D01*
Y-624669D01*
X177193Y-625469D01*
X177693Y-626269D01*
X178293Y-626803D01*
X178993Y-626936D01*
X179693Y-626669D01*
X180393Y-625870D01*
G01X185293Y-626936D02*
Y-621603D01*
G01Y-622669D02*
X185793Y-622136D01*
X186293Y-621736D01*
X186993Y-621603D01*
X187493Y-621736D01*
X188093Y-622136D01*
G01X173993Y-676936D02*
Y-668936D01*
G01X177793D02*
X173993Y-673870D01*
G01X178393Y-676936D02*
X175693Y-671603D01*
G01X185993Y-676936D02*
Y-671603D01*
G01Y-672536D02*
X185593Y-672003D01*
X184993Y-671736D01*
X184293Y-671603D01*
X183593Y-671869D01*
X182993Y-672403D01*
X182593Y-673203D01*
X182393Y-674269D01*
X182593Y-675336D01*
X182993Y-676136D01*
X183593Y-676669D01*
X184293Y-676936D01*
X184993Y-676803D01*
X185593Y-676403D01*
X185993Y-675870D01*
G01X192193Y-671603D02*
Y-676936D01*
G01Y-669469D02*
X191993Y-669336D01*
Y-669069D01*
X192193Y-668936D01*
X192393Y-669069D01*
Y-669336D01*
X192193Y-669469D01*
G01X184260Y-647922D02*
X186260D01*
Y-650322D01*
X185660Y-651122D01*
X184960Y-651655D01*
X183960Y-651922D01*
X182960Y-651655D01*
X182260Y-651122D01*
X181660Y-650322D01*
X181260Y-649389D01*
X181060Y-648322D01*
Y-647389D01*
X181260Y-646589D01*
X181660Y-645655D01*
X182260Y-644855D01*
X182860Y-644322D01*
X183660Y-643922D01*
X184360D01*
X185160Y-644189D01*
X185760Y-644722D01*
G01X189360Y-651922D02*
Y-643922D01*
X193960Y-651922D01*
Y-643922D01*
G01X197460Y-651922D02*
Y-643922D01*
X199460D01*
X200260Y-644322D01*
X200860Y-644855D01*
X201360Y-645655D01*
X201760Y-646589D01*
X201860Y-647922D01*
X201760Y-649255D01*
X201360Y-650189D01*
X200860Y-650989D01*
X200260Y-651522D01*
X199460Y-651922D01*
X197460D01*
G01X205460Y-650322D02*
X206060Y-651255D01*
X206860Y-651789D01*
X207760Y-651922D01*
X208560Y-651789D01*
X209360Y-651122D01*
X209860Y-650322D01*
X209960Y-649522D01*
X209760Y-648589D01*
X209060Y-647922D01*
X208360Y-647655D01*
X207460D01*
G01X208360D02*
X208960Y-647255D01*
X209460Y-646589D01*
X209660Y-645789D01*
X209460Y-644989D01*
X208960Y-644322D01*
X208060Y-643922D01*
X207160Y-644055D01*
X206260Y-644589D01*
G01X206202Y-627105D02*
Y-619105D01*
X205002Y-620705D01*
G01Y-627105D02*
X207402D01*
G01X214202D02*
Y-619105D01*
X213002Y-620705D01*
G01Y-627105D02*
X215402D01*
G01X279293Y-670269D02*
X279893Y-669469D01*
X280593Y-669069D01*
X281393Y-668936D01*
X282393Y-669203D01*
X283093Y-669869D01*
X283293Y-670669D01*
X283193Y-671470D01*
X282793Y-672136D01*
X280793Y-673469D01*
X279893Y-674403D01*
X279293Y-675736D01*
X279093Y-676936D01*
X283293D01*
G01X289193Y-668936D02*
X288393Y-669203D01*
X287793Y-669869D01*
X287393Y-670669D01*
X287093Y-671736D01*
X286993Y-672936D01*
X287093Y-674136D01*
X287393Y-675203D01*
X287793Y-676003D01*
X288393Y-676669D01*
X289193Y-676936D01*
X289993Y-676669D01*
X290593Y-676003D01*
X290993Y-675203D01*
X291293Y-674136D01*
X291393Y-672936D01*
X291293Y-671736D01*
X290993Y-670669D01*
X290593Y-669869D01*
X289993Y-669203D01*
X289193Y-668936D01*
G01X295293Y-670269D02*
X295893Y-669469D01*
X296593Y-669069D01*
X297393Y-668936D01*
X298393Y-669203D01*
X299093Y-669869D01*
X299293Y-670669D01*
X299193Y-671470D01*
X298793Y-672136D01*
X296793Y-673469D01*
X295893Y-674403D01*
X295293Y-675736D01*
X295093Y-676936D01*
X299293D01*
G01X303293Y-670269D02*
X303893Y-669469D01*
X304593Y-669069D01*
X305393Y-668936D01*
X306393Y-669203D01*
X307093Y-669869D01*
X307293Y-670669D01*
X307193Y-671470D01*
X306793Y-672136D01*
X304793Y-673469D01*
X303893Y-674403D01*
X303293Y-675736D01*
X303093Y-676936D01*
X307293D01*
G01X311393Y-677203D02*
X314993Y-668936D01*
G01X321193Y-676936D02*
Y-668936D01*
X319993Y-670536D01*
G01Y-676936D02*
X322393D01*
G01X327293Y-670269D02*
X327893Y-669469D01*
X328593Y-669069D01*
X329393Y-668936D01*
X330393Y-669203D01*
X331093Y-669869D01*
X331293Y-670669D01*
X331193Y-671470D01*
X330793Y-672136D01*
X328793Y-673469D01*
X327893Y-674403D01*
X327293Y-675736D01*
X327093Y-676936D01*
X331293D01*
G01X335393Y-677203D02*
X338993Y-668936D01*
G01X345193D02*
X344393Y-669203D01*
X343793Y-669869D01*
X343393Y-670669D01*
X343093Y-671736D01*
X342993Y-672936D01*
X343093Y-674136D01*
X343393Y-675203D01*
X343793Y-676003D01*
X344393Y-676669D01*
X345193Y-676936D01*
X345993Y-676669D01*
X346593Y-676003D01*
X346993Y-675203D01*
X347293Y-674136D01*
X347393Y-672936D01*
X347293Y-671736D01*
X346993Y-670669D01*
X346593Y-669869D01*
X345993Y-669203D01*
X345193Y-668936D01*
G01X351493Y-676003D02*
X352193Y-676669D01*
X352993Y-676936D01*
X353793Y-676669D01*
X354493Y-675870D01*
X354993Y-674669D01*
X355193Y-673469D01*
Y-672003D01*
X354993Y-670803D01*
X354493Y-669736D01*
X353893Y-669203D01*
X353193Y-668936D01*
X352393Y-669203D01*
X351793Y-669736D01*
X351393Y-670536D01*
X351193Y-671603D01*
X351393Y-672536D01*
X351893Y-673469D01*
X352493Y-674003D01*
X353193Y-674136D01*
X353993Y-673870D01*
X354593Y-673203D01*
X355193Y-672003D01*
G01X278993Y-651936D02*
Y-643936D01*
X280993D01*
X281793Y-644336D01*
X282393Y-644869D01*
X282893Y-645669D01*
X283293Y-646603D01*
X283393Y-647936D01*
X283293Y-649269D01*
X282893Y-650203D01*
X282393Y-651003D01*
X281793Y-651536D01*
X280993Y-651936D01*
X278993D01*
G01X286693D02*
X289193Y-643936D01*
X291693Y-651936D01*
G01X290793Y-649136D02*
X287593D01*
G01X297193Y-643936D02*
X296393Y-644203D01*
X295793Y-644869D01*
X295393Y-645669D01*
X295093Y-646736D01*
X294993Y-647936D01*
X295093Y-649136D01*
X295393Y-650203D01*
X295793Y-651003D01*
X296393Y-651669D01*
X297193Y-651936D01*
X297993Y-651669D01*
X298593Y-651003D01*
X298993Y-650203D01*
X299293Y-649136D01*
X299393Y-647936D01*
X299293Y-646736D01*
X298993Y-645669D01*
X298593Y-644869D01*
X297993Y-644203D01*
X297193Y-643936D01*
G01X303293Y-651936D02*
Y-643936D01*
X307093D01*
G01X305693Y-647803D02*
X303293D01*
G01X313193Y-643936D02*
X312393Y-644203D01*
X311793Y-644869D01*
X311393Y-645669D01*
X311093Y-646736D01*
X310993Y-647936D01*
X311093Y-649136D01*
X311393Y-650203D01*
X311793Y-651003D01*
X312393Y-651669D01*
X313193Y-651936D01*
X313993Y-651669D01*
X314593Y-651003D01*
X314993Y-650203D01*
X315293Y-649136D01*
X315393Y-647936D01*
X315293Y-646736D01*
X314993Y-645669D01*
X314593Y-644869D01*
X313993Y-644203D01*
X313193Y-643936D01*
G01X321193D02*
Y-651936D01*
G01X318893Y-643936D02*
X323493D01*
G01X326593Y-651936D02*
Y-643936D01*
X329193Y-650603D01*
X331793Y-643936D01*
Y-651936D01*
G01X334993D02*
Y-643936D01*
X336993D01*
X337793Y-644336D01*
X338393Y-644869D01*
X338893Y-645669D01*
X339293Y-646603D01*
X339393Y-647936D01*
X339293Y-649269D01*
X338893Y-650203D01*
X338393Y-651003D01*
X337793Y-651536D01*
X336993Y-651936D01*
X334993D01*
G01X347393Y-644603D02*
X346793Y-644203D01*
X346093Y-643936D01*
X345293D01*
X344393Y-644336D01*
X343693Y-645003D01*
X343193Y-645803D01*
X342793Y-647136D01*
X342693Y-648336D01*
X342893Y-649536D01*
X343193Y-650336D01*
X343793Y-651136D01*
X344493Y-651669D01*
X345193Y-651936D01*
X345893D01*
X346593Y-651669D01*
X347193Y-651269D01*
X347693Y-650736D01*
G01X350993Y-651936D02*
Y-643936D01*
X352993D01*
X353793Y-644336D01*
X354393Y-644869D01*
X354893Y-645669D01*
X355293Y-646603D01*
X355393Y-647936D01*
X355293Y-649269D01*
X354893Y-650203D01*
X354393Y-651003D01*
X353793Y-651536D01*
X352993Y-651936D01*
X350993D01*
G01X361193Y-643936D02*
X360393Y-644203D01*
X359793Y-644869D01*
X359393Y-645669D01*
X359093Y-646736D01*
X358993Y-647936D01*
X359093Y-649136D01*
X359393Y-650203D01*
X359793Y-651003D01*
X360393Y-651669D01*
X361193Y-651936D01*
X361993Y-651669D01*
X362593Y-651003D01*
X362993Y-650203D01*
X363293Y-649136D01*
X363393Y-647936D01*
X363293Y-646736D01*
X362993Y-645669D01*
X362593Y-644869D01*
X361993Y-644203D01*
X361193Y-643936D01*
G01X298418Y-624819D02*
Y-618519D01*
X301394D01*
G01X300298Y-621564D02*
X298418D01*
G01X306206Y-618519D02*
X305579Y-618729D01*
X305109Y-619254D01*
X304796Y-619884D01*
X304561Y-620724D01*
X304483Y-621669D01*
X304561Y-622614D01*
X304796Y-623454D01*
X305109Y-624084D01*
X305579Y-624609D01*
X306206Y-624819D01*
X306833Y-624609D01*
X307303Y-624084D01*
X307616Y-623454D01*
X307851Y-622614D01*
X307929Y-621669D01*
X307851Y-620724D01*
X307616Y-619884D01*
X307303Y-619254D01*
X306833Y-618729D01*
X306206Y-618519D01*
G01X312506D02*
Y-624819D01*
G01X310704Y-618519D02*
X314308D01*
G01X316456Y-626919D02*
X321156D01*
G01X323069Y-624819D02*
Y-618519D01*
X325106Y-623769D01*
X327143Y-618519D01*
Y-624819D01*
G01X332816D02*
Y-620619D01*
G01Y-621354D02*
X332503Y-620934D01*
X332033Y-620724D01*
X331484Y-620619D01*
X330936Y-620829D01*
X330466Y-621249D01*
X330153Y-621879D01*
X329996Y-622719D01*
X330153Y-623559D01*
X330466Y-624189D01*
X330936Y-624609D01*
X331484Y-624819D01*
X332033Y-624714D01*
X332503Y-624399D01*
X332816Y-623979D01*
G01X336374Y-624819D02*
Y-620619D01*
G01Y-621669D02*
X336688Y-621144D01*
X337158Y-620724D01*
X337784Y-620619D01*
X338333Y-620724D01*
X338803Y-621144D01*
X339038Y-621879D01*
Y-624819D01*
G01X345416D02*
Y-620619D01*
G01Y-621354D02*
X345103Y-620934D01*
X344633Y-620724D01*
X344084Y-620619D01*
X343536Y-620829D01*
X343066Y-621249D01*
X342753Y-621879D01*
X342596Y-622719D01*
X342753Y-623559D01*
X343066Y-624189D01*
X343536Y-624609D01*
X344084Y-624819D01*
X344633Y-624714D01*
X345103Y-624399D01*
X345416Y-623979D01*
G01X349209Y-626394D02*
X349758Y-626814D01*
X350384Y-626919D01*
X350933Y-626814D01*
X351403Y-626289D01*
X351716Y-625554D01*
Y-620619D01*
G01Y-621459D02*
X351403Y-621039D01*
X350933Y-620724D01*
X350384Y-620619D01*
X349758Y-620829D01*
X349366Y-621249D01*
X349053Y-621984D01*
X348896Y-622719D01*
X348974Y-623349D01*
X349288Y-624084D01*
X349758Y-624609D01*
X350384Y-624819D01*
X350854Y-624714D01*
X351403Y-624294D01*
X351716Y-623874D01*
G01X355431Y-621984D02*
X357938D01*
X357703Y-621249D01*
X357311Y-620829D01*
X356763Y-620619D01*
X356214Y-620724D01*
X355744Y-621039D01*
X355431Y-621774D01*
X355274Y-622404D01*
Y-623034D01*
X355431Y-623664D01*
X355823Y-624294D01*
X356293Y-624714D01*
X356841Y-624819D01*
X357389Y-624609D01*
X357938Y-623979D01*
G01X360556Y-624819D02*
Y-620619D01*
G01Y-621774D02*
X360791Y-621249D01*
X361183Y-620829D01*
X361731Y-620619D01*
X362279Y-620829D01*
X362671Y-621249D01*
X362906Y-621774D01*
Y-624819D01*
G01Y-621774D02*
X363141Y-621249D01*
X363533Y-620829D01*
X364081Y-620619D01*
X364629Y-620829D01*
X365021Y-621249D01*
X365256Y-621879D01*
Y-624819D01*
G01X368031Y-621984D02*
X370538D01*
X370303Y-621249D01*
X369911Y-620829D01*
X369363Y-620619D01*
X368814Y-620724D01*
X368344Y-621039D01*
X368031Y-621774D01*
X367874Y-622404D01*
Y-623034D01*
X368031Y-623664D01*
X368423Y-624294D01*
X368893Y-624714D01*
X369441Y-624819D01*
X369989Y-624609D01*
X370538Y-623979D01*
G01X374174Y-624819D02*
Y-620619D01*
G01Y-621669D02*
X374488Y-621144D01*
X374958Y-620724D01*
X375584Y-620619D01*
X376133Y-620724D01*
X376603Y-621144D01*
X376838Y-621879D01*
Y-624819D01*
G01X381806Y-618519D02*
Y-624819D01*
G01X380709Y-620619D02*
X382903D01*
G01X385756Y-626919D02*
X390456D01*
G01X395033Y-621459D02*
X395346Y-621144D01*
X395581Y-620619D01*
X395738Y-619884D01*
X395581Y-619254D01*
X395268Y-618834D01*
X394719Y-618519D01*
X392604D01*
Y-624819D01*
X395189D01*
X395738Y-624399D01*
X396051Y-623769D01*
X396208Y-623034D01*
X396051Y-622299D01*
X395581Y-621669D01*
X395033Y-621459D01*
X392604D01*
G01X398983Y-624819D02*
Y-618519D01*
X400549D01*
X401176Y-618834D01*
X401646Y-619254D01*
X402038Y-619884D01*
X402351Y-620619D01*
X402429Y-621669D01*
X402351Y-622719D01*
X402038Y-623454D01*
X401646Y-624084D01*
X401176Y-624504D01*
X400549Y-624819D01*
X398983D01*
G01X367693Y-679936D02*
Y-671936D01*
X366493Y-673536D01*
G01Y-679936D02*
X368893D01*
G01X373793Y-676603D02*
X374493Y-675669D01*
X375093Y-675136D01*
X375893Y-674869D01*
X376593Y-675136D01*
X377093Y-675669D01*
X377493Y-676469D01*
X377593Y-677403D01*
X377493Y-678203D01*
X377093Y-679003D01*
X376493Y-679669D01*
X375793Y-679936D01*
X374993Y-679669D01*
X374293Y-678870D01*
X373893Y-677669D01*
X373793Y-676336D01*
X373993Y-674603D01*
X374293Y-673669D01*
X374793Y-672736D01*
X375493Y-672069D01*
X376193Y-671936D01*
X376893Y-672203D01*
X377393Y-672869D01*
G01X383693Y-680203D02*
X383493Y-680069D01*
Y-679803D01*
X383693Y-679669D01*
X383893Y-679803D01*
Y-680069D01*
X383693Y-680203D01*
G01X389793Y-676603D02*
X390493Y-675669D01*
X391093Y-675136D01*
X391893Y-674869D01*
X392593Y-675136D01*
X393093Y-675669D01*
X393493Y-676469D01*
X393593Y-677403D01*
X393493Y-678203D01*
X393093Y-679003D01*
X392493Y-679669D01*
X391793Y-679936D01*
X390993Y-679669D01*
X390293Y-678870D01*
X389893Y-677669D01*
X389793Y-676336D01*
X389993Y-674603D01*
X390293Y-673669D01*
X390793Y-672736D01*
X391493Y-672069D01*
X392193Y-671936D01*
X392893Y-672203D01*
X393393Y-672869D01*
G01X412693Y-679936D02*
Y-671936D01*
X411493Y-673536D01*
G01Y-679936D02*
X413893D01*
G01X420493D02*
X420693Y-678203D01*
X420993Y-676736D01*
X421393Y-675403D01*
X421893Y-673936D01*
X422693Y-671936D01*
X418693D01*
G01X428693Y-680203D02*
X428493Y-680069D01*
Y-679803D01*
X428693Y-679669D01*
X428893Y-679803D01*
Y-680069D01*
X428693Y-680203D01*
G01X434793Y-673269D02*
X435393Y-672469D01*
X436093Y-672069D01*
X436893Y-671936D01*
X437893Y-672203D01*
X438593Y-672869D01*
X438793Y-673669D01*
X438693Y-674470D01*
X438293Y-675136D01*
X436293Y-676469D01*
X435393Y-677403D01*
X434793Y-678736D01*
X434593Y-679936D01*
X438793D01*
G01X432493Y-654936D02*
Y-646936D01*
X434493D01*
X435293Y-647336D01*
X435893Y-647869D01*
X436393Y-648669D01*
X436793Y-649603D01*
X436893Y-650936D01*
X436793Y-652269D01*
X436393Y-653203D01*
X435893Y-654003D01*
X435293Y-654536D01*
X434493Y-654936D01*
X432493D01*
M02*
